G04 ================== begin FILE IDENTIFICATION RECORD ==================*
G04 Layout Name:  F:/<user>/2022/FB/R4006-TIMING/brd/gerber-3/R4006-B0001-02_R01.brd*
G04 Film Name:    R4006-B0001-02_R01_L01*
G04 File Format:  Gerber RS274X*
G04 File Origin:  Cadence Allegro 17.2-S079*
G04 Origin Date:  Fri Feb 25 18:14:43 2022*
G04 *
G04 Layer:  ETCH/TOP*
G04 Layer:  PIN/TOP*
G04 Layer:  VIA CLASS/TOP*
G04 Layer:  MANUFACTURING/TOP*
G04 Layer:  MANUFACTURING/CELESTICA_LEGEND*
G04 *
G04 Offset:    (0.00 0.00)*
G04 Mirror:    No*
G04 Mode:      Positive*
G04 Rotation:  0*
G04 FullContactRelief:  No*
G04 UndefLineWidth:     6.00*
G04 ================== end FILE IDENTIFICATION RECORD ====================*
%FSLAX55Y55*MOIN*%
%IR0*IPPOS*OFA0.00000B0.00000*MIA0B0*SFA1.00000B1.00000*%
%AMMACRO82*
4,1,6,.0105,.00452,
.0105,.0205,
-.0105,.0205,
-.0105,-.0205,
.0015,-.0205,
.0015,.00452,
.0105,.00452,
0.0*
%
%ADD82MACRO82*%
%AMMACRO46*
4,1,6,.00452,-.0105,
.0205,-.0105,
.0205,.0105,
-.0205,.0105,
-.0205,-.0015,
.00452,-.0015,
.00452,-.0105,
0.0*
%
%ADD46MACRO46*%
%AMMACRO81*
4,1,6,.0105,-.00452,
.0105,-.0205,
-.0105,-.0205,
-.0105,.0205,
.0015,.0205,
.0015,-.00452,
.0105,-.00452,
0.0*
%
%ADD81MACRO81*%
%ADD67R,.14X.05*%
%AMMACRO58*
4,1,6,-.00452,-.0105,
-.0205,-.0105,
-.0205,.0105,
.0205,.0105,
.0205,-.0015,
-.00452,-.0015,
-.00452,-.0105,
0.0*
%
%ADD58MACRO58*%
%ADD27R,.05X.14*%
%ADD94R,.104X.045*%
%ADD96R,.045X.104*%
%ADD14C,.02*%
%ADD97R,.094X.13*%
%ADD37C,.04*%
%ADD64R,.028X.126*%
%ADD34R,.063X.118*%
%ADD16C,.024*%
%ADD71R,.008X.053*%
%ADD70R,.037X.008*%
%ADD57R,.028X.165*%
%ADD49R,.02X.02*%
%ADD11C,.09*%
%ADD10C,.018*%
%ADD98R,.031X.031*%
%ADD119C,.057*%
%ADD66R,.146X.096*%
%ADD60R,.096X.146*%
%ADD17C,.086*%
%ADD76C,.0197*%
%AMMACRO109*
4,1,8,.02619,.02281,
.02619,-.02281,
.01319,-.02281,
.01319,.01295,
-.01319,.01295,
-.01319,-.02281,
-.02619,-.02281,
-.02619,.02281,
.02619,.02281,
0.0*
%
%ADD109MACRO109*%
%AMMACRO79*
4,1,6,-.0105,-.00452,
-.0105,-.0205,
.0105,-.0205,
.0105,.0205,
-.0015,.0205,
-.0015,-.00452,
-.0105,-.00452,
0.0*
%
%ADD79MACRO79*%
%AMMACRO59*
4,1,6,-.00452,.0105,
-.0205,.0105,
-.0205,-.0105,
.0205,-.0105,
.0205,.0015,
-.00452,.0015,
-.00452,.0105,
0.0*
%
%ADD59MACRO59*%
%AMMACRO78*
4,1,6,-.0105,.00452,
-.0105,.0205,
.0105,.0205,
.0105,-.0205,
-.0015,-.0205,
-.0015,.00452,
-.0105,.00452,
0.0*
%
%ADD78MACRO78*%
%AMMACRO48*
4,1,6,.00452,.0105,
.0205,.0105,
.0205,-.0105,
-.0205,-.0105,
-.0205,.0015,
.00452,.0015,
.00452,.0105,
0.0*
%
%ADD48MACRO48*%
%ADD68R,.01X.023*%
%ADD56R,.024X.01*%
%ADD105R,.01X.024*%
%ADD77R,.012X.041*%
%ADD52R,.024X.02*%
%ADD32R,.011X.014*%
%ADD31R,.014X.011*%
%ADD106R,.02X.024*%
%ADD74R,.015X.012*%
%ADD63R,.071X.01*%
%ADD54R,.012X.024*%
%ADD47R,.041X.012*%
%ADD101R,.024X.012*%
%ADD89R,.033X.012*%
%ADD41C,.1*%
%ADD25R,.034X.03*%
%ADD23R,.012X.015*%
%ADD69R,.027X.01*%
%ADD38R,.03X.034*%
%ADD13R,.02X.018*%
%AMMACRO118*
4,1,22,.0374,.03543,
-.0374,.03543,
-.0374,-.01575,
-.0371,-.019168,
-.036212,-.022482,
-.034761,-.025591,
-.032792,-.028402,
-.030366,-.030827,
-.027555,-.032795,
-.024445,-.034244,
-.02113,-.035132,
-.01772,-.03543,
.01772,-.03543,
.021138,-.03513,
.024452,-.034242,
.027561,-.032791,
.030372,-.030822,
.032797,-.028396,
.034765,-.025585,
.036214,-.022475,
.037102,-.01916,
.0374,-.01575,
.0374,.03543,
0.0*
%
%ADD118MACRO118*%
%ADD73R,.072X.02*%
%ADD53R,.012X.045*%
%ADD110R,.013X.044*%
%ADD99R,.045X.012*%
%ADD65R,.062X.014*%
%ADD44R,.065X.02*%
%ADD39R,.064X.012*%
%ADD36R,.047X.02*%
%ADD26R,.014X.062*%
%ADD111C,.104*%
%ADD87R,.046X.012*%
%ADD85R,.012X.046*%
%ADD83R,.017X.024*%
%ADD40R,.012X.064*%
%ADD33R,.02X.047*%
%ADD22R,.012X.038*%
%ADD12R,.035X.033*%
%ADD121R,.053X.016*%
%ADD115R,.06X.018*%
%ADD107R,.049X.01*%
%ADD103R,.138X.116*%
%ADD102R,.047X.012*%
%ADD91R,.033X.017*%
%ADD90R,.025X.035*%
%ADD62R,.038X.013*%
%ADD55R,.106X.008*%
%ADD104R,.008X.106*%
%ADD72R,.055X.033*%
%ADD51R,.016X.045*%
%ADD30R,.018X.06*%
%ADD20R,.024X.028*%
%ADD15C,.115*%
%ADD100R,.045X.016*%
%ADD88R,.049X.012*%
%ADD84R,.012X.049*%
%ADD24R,.028X.024*%
%ADD21O,.075X.035*%
%AMMACRO122*
4,1,22,-.0374,-.03543,
.0374,-.03543,
.0374,.01575,
.0371,.019168,
.036212,.022482,
.034761,.025591,
.032792,.028402,
.030366,.030827,
.027555,.032795,
.024445,.034244,
.02113,.035132,
.01772,.03543,
-.01772,.03543,
-.021138,.03513,
-.024452,.034242,
-.027561,.032791,
-.030372,.030822,
-.032797,.028396,
-.034765,.025585,
-.036214,.022475,
-.037102,.01916,
-.0374,.01575,
-.0374,-.03543,
0.0*
%
%ADD122MACRO122*%
%ADD117C,.108*%
%ADD35R,.228X.244*%
%ADD29R,.039X.041*%
%ADD61C,.244*%
%ADD19R,.043X.057*%
%ADD113R,.071X.039*%
%ADD95R,.088X.04*%
%ADD80R,.071X.057*%
%ADD43R,.054X.038*%
%ADD114R,.104X.104*%
%ADD50R,.038X.054*%
%ADD45R,.057X.071*%
%ADD28R,.041X.087*%
%ADD116R,.092X.056*%
%ADD108R,.001X.001*%
%ADD75R,.055X.039*%
%ADD42R,.055X.047*%
%ADD93R,.039X.055*%
%ADD86R,.115X.115*%
%ADD92R,.071X.096*%
%ADD18R,.039X.057*%
%ADD120R,.075X.059*%
%ADD112R,.088X.056*%
%ADD123C,.01*%
%ADD124C,.012*%
%ADD125C,.015*%
%ADD126C,.005*%
%ADD127C,.006*%
%ADD128C,.008*%
%ADD129C,.0047*%
%ADD130C,.0039*%
%ADD131C,.0057*%
%ADD132C,.125*%
G75*
%LPD*%
G75*
G36*
G01X4998Y315500D02*
Y277500D01*
X3004D01*
Y315500D01*
X4998D01*
G37*
G36*
G01X4737Y351333D02*
G02X4998Y351142I61J-191D01*
G01Y336000D01*
X3004D01*
Y351142D01*
G02X3265Y351332I200J0D01*
G03X3999Y351217I734J2287D01*
G01X4000D01*
G03X4737Y351333I0J2402D01*
G37*
G36*
G01X3033Y53530D02*
X56043D01*
Y21660D01*
X55126Y20743D01*
X3827D01*
X3033Y21537D01*
Y53530D01*
G37*
G36*
G01X3947Y434591D02*
X50000D01*
Y353150D01*
X3013D01*
Y433657D01*
X3947Y434591D01*
G37*
G36*
G01X75600Y385400D02*
Y363800D01*
X74900Y363100D01*
X56400D01*
X54500Y365000D01*
Y386100D01*
X74900D01*
X75600Y385400D01*
G37*
G36*
G01X85656Y415600D02*
X101800D01*
X103300Y414100D01*
Y389600D01*
X102300Y388600D01*
X54300D01*
X53800Y389100D01*
Y414100D01*
X55300Y415600D01*
X80344D01*
G03X85656I2656J1401D01*
G37*
G36*
G01X50889Y432600D02*
G02X50699Y432861I1J200D01*
G03X50815Y433598I-2286J737D01*
G01Y433599D01*
G03X50700Y434333I-2402J0D01*
G02X50890Y434594I190J61D01*
G01X656102D01*
G02X657035Y433661I0J-933D01*
G01Y305859D01*
G02X656363Y305566I-400J0D01*
G03X655220Y306089I-1362J-1466D01*
G01X655042Y306109D01*
Y432600D01*
X50889D01*
G37*
G36*
G01X127081Y55194D02*
G02X127280Y54974I0J-200D01*
G01Y53495D01*
X126985Y53200D01*
X63894D01*
X63863Y53231D01*
Y54136D01*
G03X63700Y54921I-2400J-89D01*
G02X63887Y55194I186J73D01*
G01X127081D01*
G37*
G36*
G01X94602Y274900D02*
X99300D01*
X99800Y274400D01*
Y267400D01*
X99300Y266900D01*
X96822D01*
G03X96748Y266902I-91J-2000D01*
G01X94899D01*
X94602Y267199D01*
Y274900D01*
G37*
G36*
G01X94250Y264850D02*
X99450D01*
X100100Y264200D01*
Y256600D01*
X99300Y255800D01*
X94300D01*
X93972Y256128D01*
X94008Y256244D01*
G03X94102Y256848I-1908J606D01*
G01Y259248D01*
G03X93827Y260259I-2002J-2D01*
G01X93800Y260306D01*
Y260969D01*
X93902Y261071D01*
Y264501D01*
X94250Y264850D01*
G37*
G36*
G01X85400Y275400D02*
X91517D01*
G02X91880Y274833I0J-400D01*
G03X91698Y274000I1820J-834D01*
G01Y271600D01*
G03X91971Y270592I2002J1D01*
G03X91646Y269500I1677J-1093D01*
G01Y267100D01*
G03X91877Y266168I2002J1D01*
G01X91900Y266124D01*
Y265670D01*
X91886Y265634D01*
G03X91746Y264900I1862J-735D01*
G01Y261746D01*
X91624Y261624D01*
X88124D01*
X87867Y261881D01*
X87965Y262019D01*
G03X88502Y263700I-2365J1682D01*
G03X85600Y266602I-2902J0D01*
G01X85560D01*
G03X85169Y266632I-386J-2471D01*
G01X84368D01*
X83500Y267500D01*
X81448D01*
Y268900D01*
X84948Y272400D01*
Y274948D01*
X85400Y275400D01*
G37*
G36*
G01X82300Y386100D02*
X95500D01*
X97200Y384400D01*
Y371929D01*
G03Y368071I2299J-1929D01*
G01Y364800D01*
X95500Y363100D01*
X82300D01*
X81800Y363600D01*
Y385600D01*
X82300Y386100D01*
G37*
G36*
G01X219507Y322000D02*
X220500D01*
X221000Y321500D01*
Y313500D01*
X220000Y312500D01*
X214825D01*
G03X213120Y313452I-1705J-1051D01*
G01X208760D01*
G03X207055Y312500I0J-2003D01*
G01X205500D01*
X204000Y311000D01*
Y290000D01*
X207000Y287000D01*
X211326D01*
G03X214274I1474J2501D01*
G01X304500D01*
X309000Y282500D01*
Y269106D01*
G03X308998Y269000I3000J-110D01*
G03X309000Y268894I3002J4D01*
G01Y264606D01*
G03X308998Y264500I3000J-110D01*
G03X309000Y264394I3002J4D01*
G01Y256606D01*
G03X308998Y256500I3000J-110D01*
G03X309000Y256394I3002J4D01*
G01Y244176D01*
X308994Y244152D01*
G03X308898Y243400I2906J-753D01*
G03X308994Y242648I3002J1D01*
G01X309000Y242624D01*
Y230676D01*
X308994Y230652D01*
G03X308898Y229900I2906J-753D01*
G03X308994Y229148I3002J1D01*
G01X309000Y229124D01*
Y217500D01*
X307000Y215500D01*
X276500D01*
X268000Y207000D01*
Y161000D01*
X270500Y158500D01*
X305000D01*
X308500Y155000D01*
Y83500D01*
X305000Y80000D01*
X232000D01*
X225000Y87000D01*
X181000D01*
X174000Y80000D01*
X170643D01*
X170626Y80003D01*
G03X170240Y80036I-383J-2203D01*
G01X154246D01*
X154226Y80213D01*
G03X149454I-2386J-278D01*
G01X149434Y80036D01*
X148500D01*
G03X148114Y80003I-3J-2236D01*
G01X148097Y80000D01*
X144073D01*
G03X142070Y80802I-2003J-2100D01*
G03X140221Y80136I1J-2902D01*
G01X137670D01*
G03X136932Y80011I-1J-2236D01*
G01X136900Y80000D01*
X106000D01*
X102000Y84000D01*
Y175394D01*
G03X102002Y175500I-3000J110D01*
G03X102000Y175606I-3002J-4D01*
G01Y188394D01*
G03X102002Y188500I-3000J110D01*
G03X102000Y188606I-3002J-4D01*
G01Y197394D01*
G03X102002Y197500I-3000J110D01*
G03X102000Y197606I-3002J-4D01*
G01Y201394D01*
G03X102002Y201500I-3000J110D01*
G03X102000Y201606I-3002J-4D01*
G01Y206394D01*
G03X102002Y206500I-3000J110D01*
G03X102000Y206606I-3002J-4D01*
G01Y255669D01*
X102102Y255771D01*
Y265029D01*
X102000Y265131D01*
Y283500D01*
X106000Y287500D01*
X110838D01*
G03X114162I1662J2500D01*
G01X115838D01*
G03X119162I1662J2500D01*
G01X173460D01*
G03X173543Y287498I102J2500D01*
G01X174839D01*
X174888Y287467D01*
G03X176500Y286998I1611J2533D01*
G03X178162Y287500I0J3002D01*
G01X180361D01*
G03X184839I2239J2001D01*
G01X189000D01*
X194500Y293000D01*
Y316000D01*
X200500Y322000D01*
X212613D01*
G03X213880Y321548I1267J1550D01*
G01X218240D01*
G03X219507Y322000I0J2002D01*
G37*
G36*
G01X165200Y298100D02*
Y305000D01*
X171000D01*
Y292800D01*
X170100Y291900D01*
Y289500D01*
X143000D01*
X140500Y292000D01*
Y300600D01*
X142600Y302700D01*
X148500D01*
X149900Y301300D01*
Y293000D01*
X150400Y292500D01*
X159000D01*
X160000Y293500D01*
Y298000D01*
X165100D01*
X165200Y298100D01*
G37*
G36*
G01X147200Y315698D02*
G03X149114Y317114I0J2002D01*
G02X149350Y317250I191J-59D01*
G03X149800Y317198I453J1950D01*
G01X151702D01*
X152950Y315950D01*
Y314050D01*
X156550Y310450D01*
X158450D01*
X159750Y309150D01*
X162350D01*
X164100Y307400D01*
Y303100D01*
X164000Y303000D01*
X150800D01*
X150615Y303185D01*
X150600Y303230D01*
G03X149330Y304500I-1900J-630D01*
G01X149285Y304515D01*
X148700Y305100D01*
X143400D01*
X142836Y305664D01*
G03X143102Y306900I-2736J1235D01*
G03X142852Y308101I-3002J2D01*
G01Y314260D01*
X144191Y315600D01*
X146800D01*
X146898Y315698D01*
X147200D01*
G37*
G36*
G01X146426Y371334D02*
X153550D01*
Y370000D01*
X151550Y368000D01*
X145050D01*
X143450Y369600D01*
Y371198D01*
X145700D01*
G03X146393Y371322I-1J2002D01*
G01X146426Y371334D01*
G37*
G36*
G01X145000Y381500D02*
X154000D01*
X154500Y381000D01*
X154600D01*
Y373900D01*
X154036Y373336D01*
X146983D01*
G03X145700Y373802I-1284J-1536D01*
G01X143698D01*
X143500Y374000D01*
Y377838D01*
G03X144002Y379500I-2500J1662D01*
G03X143903Y380263I-3002J-2D01*
G01X143874Y380374D01*
X145000Y381500D01*
G37*
G36*
G01X167000Y331500D02*
X178500D01*
X180500Y329500D01*
Y323500D01*
X180908Y323092D01*
X180917Y323025D01*
G03X182625Y321317I1983J275D01*
G01X182692Y321308D01*
X182905Y321095D01*
X182853Y320971D01*
G03X182698Y320200I1847J-772D01*
G01Y317800D01*
G03X182744Y317374I2002J1D01*
G01X182768Y317268D01*
X182500Y317000D01*
X172500D01*
X170500Y315000D01*
X167500D01*
X166000Y316500D01*
Y330500D01*
X167000Y331500D01*
G37*
G36*
G01X155000Y321500D02*
X160000D01*
X161500Y320000D01*
Y313500D01*
X161000Y313000D01*
X156831D01*
X154952Y314879D01*
Y316779D01*
X154500Y317231D01*
Y321000D01*
X155000Y321500D01*
G37*
G36*
G01X154300Y329200D02*
X155400Y330300D01*
X160500D01*
X162100Y328700D01*
Y324200D01*
X161500Y323600D01*
X155800D01*
X154300Y325100D01*
Y329200D01*
G37*
G36*
G01X230800Y407000D02*
X229700Y408100D01*
X213600D01*
X213200Y408500D01*
X177000D01*
X175600Y407100D01*
Y400600D01*
X174602Y399602D01*
X165598D01*
X165166Y400034D01*
Y404659D01*
X167666Y407159D01*
Y410646D01*
G03X168461Y411450I-968J1752D01*
G01X168475Y411475D01*
X169100Y412100D01*
Y418100D01*
X169600Y418600D01*
X231900D01*
X234000Y416500D01*
Y384100D01*
X223400Y373500D01*
X173100D01*
X172600Y374000D01*
Y380600D01*
X170600Y382600D01*
Y387100D01*
X169600Y388100D01*
X165600D01*
X165100Y388600D01*
Y393100D01*
X165600Y393600D01*
X170600D01*
X179200Y385000D01*
X220700D01*
X221100Y384600D01*
X227500D01*
X230800Y387900D01*
Y388169D01*
X230802Y388171D01*
Y405700D01*
G03X230800Y405774I-2002J-17D01*
G01Y407000D01*
G37*
G36*
G01X162600Y393600D02*
X163600D01*
X164098Y393101D01*
Y388185D01*
X164100Y388184D01*
Y386600D01*
X164600Y386100D01*
X168100D01*
X168600Y385600D01*
Y381600D01*
X170100Y380100D01*
Y374100D01*
X169200Y373200D01*
X158100D01*
X157600Y373700D01*
Y384600D01*
X158100Y385100D01*
X161100D01*
X162100Y386100D01*
Y393100D01*
X162600Y393600D01*
G37*
G36*
G01X160100Y418600D02*
X165600D01*
X166600Y417600D01*
Y407600D01*
X164100Y405100D01*
Y400100D01*
X163602Y399602D01*
X162598D01*
X162100Y400100D01*
Y404800D01*
X159600Y407300D01*
Y418100D01*
X160100Y418600D01*
G37*
G36*
G01X177600Y399600D02*
Y404600D01*
X178000Y405000D01*
X189350D01*
Y390450D01*
X177950D01*
X173500Y394900D01*
X161800D01*
X161100Y395600D01*
Y398100D01*
X161600Y398600D01*
X176600D01*
X177600Y399600D01*
G37*
G36*
G01X183300Y39100D02*
X187400D01*
X188500Y38000D01*
X190500Y36000D01*
Y32500D01*
X188500Y30500D01*
Y28500D01*
X188000Y28000D01*
X183000D01*
X182400Y28600D01*
Y38200D01*
X183300Y39100D01*
G37*
G36*
G01X174000Y315000D02*
X183000D01*
X184500Y313500D01*
Y308000D01*
X183500Y307000D01*
Y306258D01*
X183473Y306211D01*
G03X183198Y305200I1727J-1013D01*
G01Y302800D01*
G03X183473Y301789I2002J2D01*
G01X183500Y301742D01*
Y301500D01*
X185305Y299695D01*
X185301Y299606D01*
G03X185298Y299500I1999J-110D01*
G01Y297693D01*
G02X184865Y297295I-400J0D01*
G03X184700Y297302I-167J-1995D01*
G01X182300D01*
G03X182164Y297297I6J-2002D01*
G02X181736Y297696I-28J399D01*
G01Y298000D01*
G03X181081Y299581I-2236J0D01*
G01X179550Y301112D01*
G03X178314Y301741I-1582J-1580D01*
G01X178249Y301751D01*
X177500Y302500D01*
X176045D01*
G03X176017Y302502I-43J-399D01*
G01X172498D01*
X172002Y302999D01*
Y306002D01*
X172000D01*
Y313000D01*
X174000Y315000D01*
G37*
G36*
G01X183500Y331500D02*
X190500D01*
X192000Y330000D01*
Y298000D01*
X190906Y296906D01*
X190770Y296991D01*
G03X189700Y297302I-1072J-1691D01*
G01X187502D01*
Y300329D01*
X187500Y300331D01*
Y300500D01*
X186000Y302000D01*
Y306000D01*
X186500Y306500D01*
Y307169D01*
X186502Y307171D01*
Y314329D01*
X186500Y314331D01*
Y314500D01*
X185000Y316000D01*
Y316669D01*
X185002Y316671D01*
Y316745D01*
X185029Y316791D01*
G03X185302Y317800I-1728J1009D01*
G01Y320200D01*
G03X185029Y321209I-2001J0D01*
G01X185002Y321255D01*
Y321829D01*
X182502Y324329D01*
Y330329D01*
X182500Y330331D01*
Y330500D01*
X183500Y331500D01*
G37*
G36*
G01X203100Y405600D02*
X228000D01*
X228800Y404800D01*
Y389000D01*
X227400Y387600D01*
X219856D01*
G03X218800Y387902I-1057J-1700D01*
G01X216400D01*
G03X215344Y387600I1J-2002D01*
G01X203100D01*
X202100Y388600D01*
Y404600D01*
X203100Y405600D01*
G37*
G36*
G01X350575Y358392D02*
X348132Y355949D01*
X299671D01*
X297872Y357748D01*
Y379313D01*
X310598D01*
X323412Y366500D01*
X328000D01*
X328331Y366169D01*
X350350D01*
X350575Y365944D01*
Y358392D01*
G37*
G36*
G01X337716Y403200D02*
X338000D01*
X338400Y402800D01*
Y399600D01*
X338000Y399200D01*
X334716D01*
X334715Y399202D01*
X324885D01*
X324884Y399200D01*
X323300D01*
X322300Y398200D01*
Y398194D01*
X317571Y393465D01*
X297812D01*
X297784Y393493D01*
Y403070D01*
X297914Y403200D01*
X328884D01*
X328885Y403198D01*
X334615D01*
X334616Y403200D01*
X335284D01*
X335285Y403198D01*
X337715D01*
X337716Y403200D01*
G37*
G36*
G01X618926Y55194D02*
G02X619116Y54933I-1J-200D01*
G03X619000Y54197I2286J-737D01*
G01Y54196D01*
G03X619115Y53462I2402J0D01*
G02X618925Y53201I-190J-61D01*
G01X316142D01*
G03X309201Y46260I0J-6941D01*
G01Y26200D01*
X307944D01*
Y26792D01*
G03X307236Y28425I-2237J0D01*
G01Y46979D01*
G02X316142Y55194I8906J-720D01*
G01X618926D01*
G37*
G36*
G01X334200Y404200D02*
X329300D01*
X320300Y413200D01*
Y424200D01*
X320800Y424700D01*
X326800D01*
X327300Y424200D01*
Y417200D01*
X329300Y415200D01*
Y410700D01*
X330300Y409700D01*
X334000D01*
X334600Y409100D01*
Y404600D01*
X334200Y404200D01*
G37*
G36*
G01X337500Y251500D02*
X345898D01*
Y249400D01*
G03X347400Y247898I1502J0D01*
G01X350500D01*
Y239500D01*
X350001Y239001D01*
X349974Y238987D01*
G03X349341Y238500I1025J-1988D01*
G01X348500D01*
X347500Y239500D01*
Y243000D01*
X345800Y244700D01*
X338800D01*
X337500Y246000D01*
Y251500D01*
G37*
G36*
G01X325300Y398200D02*
X334300D01*
X334800Y397700D01*
Y393200D01*
X334300Y392700D01*
X333300D01*
X332300Y391700D01*
Y387200D01*
X332275Y387175D01*
G03X331425Y386325I925J-1775D01*
G01X330800Y385700D01*
Y379700D01*
X331425Y379075D01*
G03X332275Y378225I1775J925D01*
G01X334462Y376038D01*
X343358D01*
X346687Y372709D01*
X350462D01*
X350543Y372628D01*
Y369206D01*
X329269D01*
X329161Y369098D01*
X329091Y369091D01*
G03X328385Y368880I210J-1991D01*
G03X326700Y369802I-1685J-1079D01*
G01X324300D01*
Y397200D01*
X325300Y398200D01*
G37*
G36*
G01X336100Y398000D02*
X337400D01*
Y391000D01*
X340300Y388100D01*
Y379700D01*
X339800Y379200D01*
X334300D01*
X333300Y380200D01*
Y386784D01*
X333302Y386785D01*
Y389702D01*
X335900Y392300D01*
Y397800D01*
X336100Y398000D01*
G37*
G36*
G01X330300Y425200D02*
X341800D01*
X342300Y424700D01*
Y413200D01*
X341800Y412700D01*
X338800D01*
X337800Y411700D01*
Y404700D01*
X337300Y404200D01*
X335700D01*
X335602Y404298D01*
Y409515D01*
X335400Y409716D01*
Y411300D01*
X335000Y411700D01*
X331800D01*
X331300Y412200D01*
Y416200D01*
X329800Y417700D01*
Y424700D01*
X330300Y425200D01*
G37*
G36*
G01X349000Y158500D02*
X359000D01*
X362000Y155500D01*
Y144000D01*
X356662D01*
G03X356289Y144211I-1661J-2501D01*
G01X349000Y151500D01*
Y158500D01*
G37*
G36*
G01X349500Y170500D02*
X370700D01*
X372950Y168250D01*
Y167550D01*
X373000Y167500D01*
Y162102D01*
X367800D01*
G03X367199Y162009I2J-2002D01*
G01X367170Y162000D01*
X356000D01*
X355000Y163000D01*
X348500D01*
Y169500D01*
X349500Y170500D01*
G37*
G36*
G01X354749Y226748D02*
X362751D01*
X363000Y226500D01*
Y216500D01*
X355000D01*
X354000Y217500D01*
Y226000D01*
X354749Y226748D01*
G37*
G36*
G01X356000Y252000D02*
X356500Y251500D01*
Y247000D01*
X356000Y246500D01*
X354000D01*
X353500Y247000D01*
Y252000D01*
X356000D01*
G37*
G36*
G01X347800Y262400D02*
X355000D01*
X355524Y261876D01*
X355514Y261780D01*
G03X355498Y261500I2486J-283D01*
G03X356000Y259997I2501J0D01*
G01Y254702D01*
X353400D01*
G03X352670Y254564I0J-2002D01*
G01X352635Y254550D01*
X347950D01*
X347200Y255300D01*
Y260600D01*
X347250Y260650D01*
Y261850D01*
X347800Y262400D01*
G37*
G36*
G01X346100Y425100D02*
X356300D01*
X356800Y424600D01*
Y422502D01*
G03X355998Y420900I1199J-1602D01*
G01Y418500D01*
G03X356800Y416898I2001J0D01*
G01Y415400D01*
X356102Y414702D01*
X354743D01*
G03X353277Y414249I1J-2602D01*
G03X352657Y414336I-618J-2149D01*
G01X350463D01*
G03X349283Y414000I-1J-2236D01*
G01X346700D01*
X345300Y415400D01*
Y424300D01*
X346100Y425100D01*
G37*
G36*
G01X367000Y144500D02*
Y158500D01*
X379000D01*
X379500Y158000D01*
Y147812D01*
X378134Y146446D01*
X375096D01*
X373150Y144500D01*
X367000D01*
G37*
G36*
G01X368500Y228000D02*
X377500D01*
X379500Y226000D01*
Y217500D01*
X378500Y216500D01*
X368000D01*
Y227500D01*
X368500Y228000D01*
G37*
G36*
G01X361200Y298200D02*
X369100D01*
X370200Y297100D01*
X377200D01*
X377500Y297400D01*
X383384D01*
X383385Y297398D01*
X390115D01*
X390116Y297400D01*
X398100D01*
X398500Y297000D01*
Y286200D01*
X398200Y285900D01*
X394900D01*
X394500Y286300D01*
Y291200D01*
X394000Y291700D01*
X383200D01*
X382500Y291000D01*
Y288500D01*
X381983Y287983D01*
G03X380900Y288302I-1084J-1683D01*
G01X378500D01*
G03X377175Y287800I1J-2002D01*
G01X376400D01*
X376000Y287400D01*
Y285300D01*
X375700Y285000D01*
X361402D01*
Y287000D01*
G03X360900Y288326I-2002J0D01*
G03X360902Y288400I-1500J78D01*
G01Y291200D01*
G03X360500Y292222I-1502J-1D01*
G01Y297500D01*
X361200Y298200D01*
G37*
G36*
G01X380200Y280202D02*
G03X378698Y278700I0J-1502D01*
G01Y276888D01*
G02X378263Y276490I-400J0D01*
G03X378000Y276502I-268J-2990D01*
G03X375169Y274500I0J-3003D01*
G01X365135D01*
X365121Y274502D01*
G03X364720Y274532I-405J-2722D01*
G01X364468D01*
X363400Y275600D01*
Y281500D01*
X364200Y282300D01*
X376300D01*
X377400Y283400D01*
Y284224D01*
X377418Y284263D01*
G03X377602Y285100I-1818J838D01*
G01Y285351D01*
G02X378084Y285742I400J0D01*
G03X378500Y285698I417J1958D01*
G01X380900D01*
G03X382422Y286400I0J2001D01*
G01X383900D01*
X384700Y287200D01*
Y290000D01*
X385200Y290500D01*
X389800D01*
Y285500D01*
X386500Y282200D01*
X383600D01*
X383100Y281700D01*
Y280242D01*
G03X383055Y280202I1317J-1527D01*
G01X380200D01*
G37*
G36*
G01X360700Y312100D02*
X366700D01*
X367298Y311502D01*
Y304071D01*
X367400Y303969D01*
Y301002D01*
X365000D01*
G03X363570Y300400I1J-2002D01*
G01X361000D01*
X360300Y301100D01*
Y311700D01*
X360700Y312100D01*
G37*
G36*
G01X369700Y312000D02*
X373100D01*
X373300Y311800D01*
Y311244D01*
X373250Y311187D01*
G03X372498Y309200I2249J-1987D01*
G03X374643Y306323I3002J0D01*
G01X374692Y306308D01*
X375000Y306000D01*
X377826D01*
G03X377900Y305998I91J2000D01*
G01X380700D01*
G03X380774Y306000I-17J2002D01*
G01X382026D01*
G03X382100Y305998I91J2000D01*
G01X384900D01*
G03X384974Y306000I-17J2002D01*
G01X387000D01*
X389800Y303200D01*
Y298500D01*
X389700Y298400D01*
X383800D01*
X382300Y299900D01*
X382104D01*
X382052Y299936D01*
G03X380900Y300302I-1154J-1635D01*
G01X378500D01*
G03X377298Y299900I1J-2002D01*
G01X370600D01*
X370300Y300200D01*
Y303900D01*
X369300Y304900D01*
Y311600D01*
X369700Y312000D01*
G37*
G36*
G01X359300Y424200D02*
X363800D01*
X364200Y423800D01*
Y417600D01*
X363800Y417200D01*
X359300D01*
X358802Y417698D01*
Y423702D01*
X359300Y424200D01*
G37*
G36*
G01X414700Y276900D02*
X409500D01*
X407900Y278500D01*
Y295500D01*
X409300Y296900D01*
X414600D01*
X415200Y296300D01*
Y277400D01*
X414700Y276900D01*
G37*
G36*
G01X417850Y297250D02*
X417864Y297264D01*
X430236D01*
X430900Y296600D01*
Y281700D01*
X430500Y281300D01*
X427400D01*
X426700Y280600D01*
Y276200D01*
X426200Y275700D01*
X418000D01*
X417356Y276344D01*
G02X417352Y276623I141J142D01*
G03X417902Y278000I-1452J1378D01*
G01Y280400D01*
G03X417658Y281358I-2003J0D01*
G01X417850Y281550D01*
Y297250D01*
G37*
G36*
G01X438000Y270698D02*
X439802D01*
X441500Y269000D01*
X448000D01*
Y263000D01*
X447406Y262406D01*
X439292D01*
X438000Y263699D01*
Y270698D01*
G37*
G36*
G01X433000Y293900D02*
X438800D01*
X439200Y293500D01*
Y285700D01*
X439000Y285500D01*
Y281500D01*
X440500Y280000D01*
X446894D01*
G03X447000Y279998I110J3000D01*
G03X447106Y280000I-4J3002D01*
G01X447500D01*
X448500Y279000D01*
Y272500D01*
X442500D01*
X441500Y273500D01*
X432600D01*
X432100Y274000D01*
Y293000D01*
X433000Y293900D01*
G37*
G36*
G01X458500Y387500D02*
X461000D01*
Y381500D01*
X462500Y380000D01*
Y349500D01*
X474000Y338000D01*
Y305000D01*
X466500Y297500D01*
X463825D01*
X460243Y301081D01*
G03X459885Y301372I-1582J-1580D01*
G03X458836Y302518I-1885J-672D01*
G01Y303614D01*
X458878Y303668D01*
G03X459501Y305423I-2378J1832D01*
G01X459503Y305503D01*
X462048Y308048D01*
X462106Y308060D01*
G03X464502Y311000I-606J2940D01*
G03X462500Y313831I-3003J0D01*
G01Y321894D01*
G03X462502Y322000I-3000J110D01*
G03X462500Y322106I-3002J-4D01*
G01Y327000D01*
X459500Y330000D01*
X457375D01*
G03X456500Y330202I-876J-1800D01*
G01X453700D01*
G03X452825Y330000I1J-2002D01*
G01X449500D01*
X448000Y331500D01*
Y342500D01*
X452000Y346500D01*
Y360500D01*
X447500Y365000D01*
Y371900D01*
G03X449001Y374423I-1500J2600D01*
G01X449003Y374503D01*
X452000Y377500D01*
Y385698D01*
X454200D01*
G03X455209Y385971I0J2001D01*
G01X455255Y385998D01*
X455829D01*
X455831Y386000D01*
X457000D01*
X458500Y387500D01*
G37*
G36*
G01X452500Y398000D02*
X459500D01*
X460000Y397500D01*
Y390000D01*
X457000D01*
X455095Y388095D01*
X454971Y388147D01*
G03X454200Y388302I-772J-1847D01*
G01X452000D01*
Y397500D01*
X452500Y398000D01*
G37*
G36*
G01X478500Y238000D02*
X470500D01*
X468400Y240100D01*
Y246100D01*
X468700Y246400D01*
X479300D01*
X479800Y245900D01*
Y239300D01*
X478500Y238000D01*
G37*
G36*
G01X468300Y260100D02*
X469000Y260800D01*
X478800D01*
X479500Y260100D01*
Y251900D01*
X478900Y251300D01*
X468700D01*
X468300Y251700D01*
Y260100D01*
G37*
G36*
G01X463900Y384500D02*
Y396100D01*
X464500Y396700D01*
X482700D01*
X483000Y396400D01*
Y389000D01*
X482600Y388600D01*
X471600D01*
X467500Y384500D01*
X463900D01*
G37*
G36*
G01X491700Y248100D02*
X502198D01*
Y246200D01*
G03X502800Y244770I2002J1D01*
G01Y240200D01*
X502200Y239600D01*
X492000D01*
X491400Y240200D01*
Y247800D01*
X491700Y248100D01*
G37*
G36*
G01X502200Y269300D02*
X506800D01*
Y263200D01*
X506415Y262815D01*
X506370Y262800D01*
G03X504998Y260900I630J-1900D01*
G01Y258500D01*
G03X505111Y257840I2001J3D01*
G03X504162Y256601I989J-1740D01*
G01X504149Y256549D01*
X503550Y255950D01*
Y251100D01*
X503052Y250602D01*
X500000D01*
G03X499398Y250509I1J-2002D01*
G01X499368Y250500D01*
X491600D01*
X490900Y251200D01*
Y254900D01*
X491900Y255900D01*
X497900D01*
X499300Y257300D01*
Y266400D01*
X502200Y269300D01*
G37*
G36*
G01X487500Y394500D02*
X488500Y395500D01*
X512500D01*
X513500Y394500D01*
Y389500D01*
X513000Y389000D01*
X487500D01*
Y394500D01*
G37*
G36*
G01X511500Y176500D02*
X518500D01*
Y167500D01*
X521500Y164500D01*
Y128000D01*
X522000Y127500D01*
Y121500D01*
X514500D01*
X512000Y124000D01*
Y160500D01*
X511236Y161264D01*
Y168500D01*
G03X511000Y169501I-2236J1D01*
G01Y176000D01*
X511500Y176500D01*
G37*
G36*
G01X508289Y277427D02*
X518101D01*
X518783Y276745D01*
Y274000D01*
X514100D01*
X513600Y273500D01*
Y269716D01*
X513598Y269715D01*
Y264185D01*
X513600Y264184D01*
Y263600D01*
X513650Y263550D01*
Y261950D01*
X514300Y261300D01*
X516600D01*
X517048Y260852D01*
X517029Y260750D01*
G03X516998Y260400I1971J-351D01*
G01Y258000D01*
G03X517500Y256675I2002J1D01*
G01Y255170D01*
X518100Y254570D01*
Y240100D01*
X517400Y239400D01*
X505200D01*
X504997Y239603D01*
X505038Y239721D01*
G03X505202Y240700I-2838J979D01*
G03X504802Y242198I-3002J1D01*
G01Y247802D01*
X506000Y249000D01*
Y256000D01*
X507550Y257550D01*
Y258048D01*
X507555Y258070D01*
G03X507602Y258500I-1955J431D01*
G01Y260900D01*
G03X507592Y261090I-2001J-10D01*
G01X507584Y261184D01*
X507900Y261500D01*
Y275800D01*
X507944Y275844D01*
Y277082D01*
X508289Y277427D01*
G37*
G36*
G01X523100Y266321D02*
Y263100D01*
X523600Y262600D01*
X525058D01*
G03X525098Y262555I1527J1317D01*
G01Y259700D01*
G03X525696Y258501I1501J0D01*
G01X525708Y258492D01*
X526600Y257600D01*
Y257400D01*
X527519Y256481D01*
X527534Y256440D01*
G03X529000Y254799I2816J1040D01*
G01Y247500D01*
X526500Y245000D01*
X522500D01*
X520700Y246800D01*
Y254800D01*
X519960Y255540D01*
X519945Y255576D01*
G03X519352Y256362I-1845J-775D01*
G02X519269Y256895I250J312D01*
G03X519602Y258000I-1669J1106D01*
G01Y260400D01*
G03X518900Y261922I-2001J0D01*
G01Y263400D01*
X518100Y264200D01*
X515000D01*
X514600Y264600D01*
Y269300D01*
X514800Y269500D01*
X520092D01*
G03X520560Y268860I2310J1198D01*
G01X523100Y266321D01*
G37*
G36*
G01X510500Y386500D02*
X519000D01*
X520235Y385265D01*
X520198Y385229D01*
Y372698D01*
X520000Y372500D01*
X513000D01*
X512500Y373000D01*
Y379500D01*
X510500Y381500D01*
Y386500D01*
G37*
G36*
G01X507500Y381000D02*
X509500Y379000D01*
Y375500D01*
X508500Y374500D01*
X503500D01*
X502500Y375500D01*
Y385500D01*
X507500D01*
Y381000D01*
G37*
G36*
G01X567500Y205500D02*
X572549D01*
G03X573300Y205298I752J1300D01*
G01X578500D01*
Y198000D01*
X577500Y197000D01*
Y157500D01*
X572000Y152000D01*
X542000D01*
X538000Y148000D01*
Y125000D01*
X534500Y121500D01*
X525500D01*
Y126000D01*
X527500Y128000D01*
Y164500D01*
X533500D01*
X534525Y163475D01*
X534539Y163450D01*
G03X535350Y162639I1761J950D01*
G01X535375Y162625D01*
X535500Y162500D01*
X535669D01*
X535671Y162498D01*
X535675D01*
X535704Y162489D01*
G03X536300Y162398I597J1911D01*
G01X541700D01*
G03X542296Y162489I-1J2002D01*
G01X542325Y162498D01*
X546502D01*
X553000Y156000D01*
X553669D01*
X553671Y155998D01*
X566829D01*
X566831Y156000D01*
X569000D01*
X570500Y157500D01*
Y200000D01*
X569002Y201498D01*
Y202802D01*
X567698D01*
X567500Y203000D01*
Y205500D01*
G37*
G36*
G01X567000Y178000D02*
Y159000D01*
X566000Y158000D01*
X554500D01*
X548000Y164500D01*
X536500D01*
X532500Y168500D01*
X523500D01*
Y178500D01*
X525000Y180000D01*
X565000D01*
X567000Y178000D01*
G37*
G36*
G01X549000Y213972D02*
X549728Y214700D01*
X553800D01*
X554500Y214000D01*
Y209500D01*
X550500Y205500D01*
X547000D01*
X544000Y202500D01*
Y183500D01*
X543500Y183000D01*
X540000D01*
X539000Y184000D01*
X532500D01*
Y207000D01*
X533000Y207500D01*
X541500D01*
X543500Y209500D01*
X548000D01*
X549000Y210500D01*
Y213972D01*
G37*
G36*
G01X529486Y224600D02*
X531826D01*
G03X531900Y224598I91J2000D01*
G01X534302D01*
X534600Y224300D01*
Y219000D01*
X534300Y218700D01*
X529000D01*
X528600Y219100D01*
Y224300D01*
X528798Y224498D01*
X528875Y224503D01*
G03X529462Y224594I-164J2997D01*
G01X529486Y224600D01*
G37*
G36*
G01X533400Y236500D02*
X542000D01*
X543100Y235400D01*
Y227900D01*
X542200Y227000D01*
X536600D01*
X536500Y226900D01*
X535356D01*
G03X534300Y227202I-1057J-1700D01*
G01X532110D01*
G02X531711Y227590I1J400D01*
G03X530400Y229981I-3001J-90D01*
G01Y233500D01*
X533400Y236500D01*
G37*
G36*
G01X527298Y356498D02*
X538502D01*
X540500Y354500D01*
Y318000D01*
X539900Y317400D01*
X526300D01*
X525700Y318000D01*
Y354900D01*
X527298Y356498D01*
G37*
G36*
G01X523300Y385500D02*
X530900D01*
X531700Y384700D01*
Y379600D01*
X532398Y378902D01*
Y378871D01*
X534271Y376998D01*
X536102D01*
X536500Y376600D01*
Y372300D01*
X536000Y371800D01*
X523200D01*
X522200Y372800D01*
Y384400D01*
X523300Y385500D01*
G37*
G36*
G01X543498Y379998D02*
X550400D01*
Y360340D01*
X549400Y359340D01*
Y355100D01*
X545300D01*
X541900Y358500D01*
X523000D01*
X522500Y359000D01*
Y369100D01*
X536200D01*
X537225Y370125D01*
G03X538075Y370975I-925J1775D01*
G01X542500Y375400D01*
Y379000D01*
X543498Y379998D01*
G37*
G36*
G01X526400Y400200D02*
X532300D01*
X533000Y399500D01*
Y397775D01*
G03X532798Y396900I1800J-876D01*
G01Y394500D01*
G03X533000Y393625I2002J1D01*
G01Y392400D01*
X532800Y392200D01*
Y388600D01*
X532100Y387900D01*
X526500D01*
X525500Y388900D01*
Y399300D01*
X526400Y400200D01*
G37*
G36*
G01X543500Y89000D02*
X550300D01*
Y82800D01*
X552400Y80700D01*
X553800D01*
X554400Y80100D01*
Y75200D01*
X555200Y74400D01*
X558300D01*
X558700Y74000D01*
Y69300D01*
X558500Y69100D01*
X552400D01*
X551702Y69798D01*
X551689Y69857D01*
G03X549957Y71589I-2189J-457D01*
G01X549898Y71602D01*
X542500Y79000D01*
Y88000D01*
X543500Y89000D01*
G37*
G36*
G01X537700Y224400D02*
X545300D01*
X546000Y223700D01*
Y219000D01*
X547000Y218000D01*
X554000D01*
X554500Y217500D01*
Y216500D01*
X554000Y216000D01*
X547600D01*
X547000Y215400D01*
Y212900D01*
X546300Y212200D01*
X543212D01*
X542512Y211500D01*
X542500D01*
X541000Y210000D01*
X536000D01*
X535200Y210800D01*
Y216769D01*
X536602Y218171D01*
Y218402D01*
X537000Y218800D01*
Y223700D01*
X537700Y224400D01*
G37*
G36*
G01X535800Y392100D02*
X541500D01*
X542100Y391500D01*
Y386700D01*
X545000Y383800D01*
X550100D01*
X550300Y383600D01*
Y381200D01*
X550100Y381000D01*
X542300D01*
X540300Y379000D01*
X535100D01*
X534610Y379490D01*
X534601Y379501D01*
G03X534400Y379743I-2407J-1794D01*
G01Y387175D01*
G03X534675Y387575I-1500J1326D01*
G01X535300Y388200D01*
Y391600D01*
X535800Y392100D01*
G37*
G36*
G01X553800Y94700D02*
X565300D01*
Y82700D01*
X566300Y81700D01*
Y77000D01*
X565300Y76000D01*
Y75616D01*
X565198Y75515D01*
Y68885D01*
X565300Y68784D01*
Y61469D01*
X564707Y60876D01*
X556542D01*
X554487Y62931D01*
Y64554D01*
X558750D01*
X558796Y64600D01*
X558800D01*
X559600Y65400D01*
Y68784D01*
X559702Y68885D01*
Y74415D01*
X558715Y75402D01*
X558598D01*
X558200Y75800D01*
X556100D01*
X555500Y76400D01*
Y81400D01*
X554700Y82200D01*
X553200D01*
X552700Y82700D01*
Y93661D01*
X553800Y94700D01*
G37*
G36*
G01X566200Y69300D02*
Y75100D01*
X567900Y76800D01*
Y94500D01*
X568400Y95000D01*
X571900D01*
X572700Y94200D01*
Y89700D01*
X574000Y88400D01*
Y69500D01*
X573600Y69100D01*
X566400D01*
X566200Y69300D01*
G37*
G36*
G01X556500Y104000D02*
X570500D01*
X571500Y103000D01*
Y97500D01*
X566256D01*
G03X565200Y97802I-1057J-1700D01*
G01X562800D01*
G03X561744Y97500I1J-2002D01*
G01X555500D01*
Y103000D01*
X556500Y104000D01*
G37*
G36*
G01X556000Y219000D02*
X559000D01*
X559500Y218500D01*
Y217916D01*
X559498Y217915D01*
Y216085D01*
X559500Y216084D01*
Y205500D01*
X564200Y200800D01*
X567000D01*
Y190750D01*
X552500D01*
Y202500D01*
X555500Y205500D01*
Y209084D01*
X555502Y209085D01*
Y214415D01*
X555500Y214416D01*
Y216084D01*
X555502Y216085D01*
Y217915D01*
X555500Y217916D01*
Y218500D01*
X556000Y219000D01*
G37*
G36*
G01X568400Y212200D02*
X571197D01*
X572785Y210612D01*
X578648D01*
Y204057D01*
X577591Y203000D01*
X564500D01*
X561500Y206000D01*
Y215000D01*
X565600D01*
X568400Y212200D01*
G37*
G36*
G01X573236Y221200D02*
X576000D01*
X576600Y220600D01*
Y215100D01*
X575000Y213500D01*
X568700D01*
X568300Y213900D01*
Y214400D01*
X566700Y216000D01*
X566016D01*
X566015Y216002D01*
X560998D01*
X560500Y216500D01*
Y217500D01*
X561000Y218000D01*
X567500D01*
X568000Y218500D01*
Y219071D01*
G03X568352Y219973I-1050J929D01*
G01X568353Y220053D01*
X569127Y220827D01*
X569240Y220795D01*
G03X569943Y220698I704J2505D01*
G01X571700D01*
G03X573236Y221200I0J2601D01*
G37*
G36*
G01X551700Y380700D02*
X556000D01*
X556300Y380400D01*
Y360300D01*
X556800Y359800D01*
X560200D01*
X560699Y359301D01*
G03X560298Y358100I1601J-1202D01*
G01Y355700D01*
G03X560900Y354270I2002J1D01*
G01Y353483D01*
X560887Y353449D01*
G03X560698Y352400I2813J-1048D01*
G03X560900Y351317I3002J0D01*
G01Y348900D01*
X561900Y347900D01*
X562000D01*
X562999Y346901D01*
X563003Y346825D01*
G03X565000Y344169I2997J175D01*
G01Y320600D01*
X563000Y318600D01*
X552000D01*
X551000Y319600D01*
Y352500D01*
X551500Y353000D01*
Y358500D01*
X551000Y359000D01*
Y359524D01*
X551402Y359925D01*
Y380402D01*
X551700Y380700D01*
G37*
G36*
G01X602500Y211250D02*
X599000D01*
X598500Y211750D01*
Y216750D01*
X595500D01*
Y215750D01*
X591000Y211250D01*
X580500Y200750D01*
Y196750D01*
X580000Y196250D01*
X579500Y195750D01*
Y194250D01*
X582500Y191250D01*
X583500D01*
X584000Y191750D01*
Y194250D01*
X584500Y194750D01*
X588000Y198250D01*
Y201250D01*
X594500Y207750D01*
X602500D01*
Y211250D01*
G37*
G36*
G01X638600Y227874D02*
X654700D01*
X657000Y225574D01*
Y195474D01*
X655400Y193874D01*
X619800D01*
X619200Y194474D01*
Y197974D01*
X619900Y198674D01*
X626098D01*
G03X627700Y197872I1602J1199D01*
G01X630100D01*
G03X631702Y198674I0J2001D01*
G01X634200D01*
X635100Y199574D01*
Y199674D01*
X638298Y202872D01*
X643929D01*
X643931Y202874D01*
X646400D01*
X647600Y204074D01*
Y217874D01*
X646700Y218774D01*
X638800D01*
X637400Y220174D01*
Y226674D01*
X638600Y227874D01*
G37*
G36*
G01X636898Y205078D02*
G02X636698Y204874I-200J-4D01*
G01X636300D01*
X632300Y200874D01*
X625830D01*
X625801Y200883D01*
G03X625200Y200976I-603J-1909D01*
G01X619800D01*
G03X619374Y200930I1J-2002D01*
G01X619268Y200906D01*
X618800Y201374D01*
Y206074D01*
X619600Y206874D01*
X626524D01*
G03X627989Y206664I1467J5019D01*
G01X635925D01*
G03X636898Y206247I1592J2371D01*
G01Y205078D01*
G37*
G36*
G01X620551Y90157D02*
X656988D01*
Y54059D01*
X656177Y53248D01*
X620500D01*
Y54134D01*
X620551D01*
Y90157D01*
G37*
G36*
G01Y434560D02*
X656272D01*
X657019Y433813D01*
Y392520D01*
X620551D01*
Y434560D01*
G37*
G36*
G01X652087Y242521D02*
X652239Y242484D01*
Y241437D01*
G03X657035Y236468I4972J0D01*
G01Y230000D01*
X655042D01*
Y234818D01*
G02X650306Y240517I2169J6620D01*
G01Y240935D01*
G03X650246Y241421I-2001J0D01*
G01Y242711D01*
G02X650862Y243047I400J-1D01*
G03X652087Y242521I2190J3410D01*
G37*
G36*
G01X655042Y191500D02*
X657035D01*
Y92200D01*
X655042D01*
Y191500D01*
G37*
%LPC*%
G75*
G36*
G01X131526Y98897D02*
G03X130906Y98982I-344J-204D01*
G02X126067Y97041I-4839J5061D01*
G02Y111045I0J7002D01*
G02X129639Y110065I-1J-7002D01*
G03X130224Y110288I204J344D01*
G02X143567Y120044I13342J-4245D01*
G02Y92042I0J-14001D01*
G02X131526Y98897I-1J14001D01*
G37*
G36*
G01X261925Y99161D02*
G03X261885Y99839I-231J327D01*
G02X254566Y112143I6683J12304D01*
G02X282568I14001J0D01*
G02X277238Y101149I-14001J-1D01*
G03X277506Y100436I248J-314D01*
G02X277867Y100445I355J-6993D01*
G02Y86441I0J-7002D01*
G02X272239Y89278I0J7001D01*
G03X271595I-322J-238D01*
G02X265967Y86441I-5628J4164D01*
G02X260291Y89343I0J7002D01*
G03X259643I-324J-235D01*
G02X253967Y86441I-5676J4100D01*
G02Y100445I0J7002D01*
G02X259643Y97543I0J-7002D01*
G03X260291I324J235D01*
G02X261925Y99161I5677J-4099D01*
G37*
G36*
G01X283070Y257715D02*
G03X282501Y257314I-171J-362D01*
G02X282568Y255943I-13934J-1368D01*
G02X268567Y269944I-14001J0D01*
G02X278629Y265679I0J-14002D01*
G03X279303Y265854I288J278D01*
G02X286067Y271045I6764J-1811D01*
G02Y257041I0J-7002D01*
G02X283070Y257715I0J7002D01*
G37*
G36*
G01X131385Y268598D02*
G03X132088Y268836I304J260D01*
G02X146067Y282044I13979J-794D01*
G02Y254042I0J-14001D01*
G02X133468Y261935I0J14002D01*
G03X132728Y261884I-360J-175D01*
G02X126067Y257041I-6661J2159D01*
G02Y271045I0J7002D01*
G02X131385Y268598I0J-7002D01*
G37*
%LPD*%
G75*
G36*
G01X155567Y106043D02*
G03I-12000J0D01*
G37*
G36*
G01X158067Y268043D02*
G03I-12000J0D01*
G37*
G36*
G01X280567Y112143D02*
G03I-12000J0D01*
G37*
G36*
G01Y255943D02*
G03I-12000J0D01*
G37*
%LPC*%
G75*
G54D132*
X143567Y106043D03*
X146067Y268043D03*
X268567Y112143D03*
Y255943D03*
%LPD*%
G75*
G54D100*
X552087Y216878D03*
X562913D03*
G54D110*
X551631Y383456D03*
X555569D03*
G54D101*
X551004Y219240D03*
X563996D03*
G54D120*
X651582Y214961D03*
Y207087D03*
G54D102*
X547929Y365826D03*
Y367794D03*
Y369763D03*
Y371731D03*
Y373700D03*
Y375669D03*
Y377637D03*
Y379606D03*
Y381574D03*
X559271Y371731D03*
Y369763D03*
Y367794D03*
Y365826D03*
Y381574D03*
Y379606D03*
Y377637D03*
Y375669D03*
Y373700D03*
G54D111*
X588779Y334449D03*
Y350984D03*
Y367519D03*
X605315Y334449D03*
Y350984D03*
G54D130*
G01X312300Y175000D02*
X310972Y176328D01*
G03X309592Y176900I-1380J-1379D01*
G01X307711D01*
G03X307180Y176680I0J-751D01*
G01X301872Y171372D01*
G02X300492Y170800I-1380J1379D01*
G01X288710D01*
G02X287330Y171372I0J1951D01*
G01X283354Y175348D01*
G03X282823Y175568I-531J-531D01*
G01X282354D01*
G03X281956Y175403I0J-563D01*
G01X281902Y175349D01*
G02X281504Y175184I-398J398D01*
G01X276986D01*
G01X312300Y180000D02*
X310972Y178672D01*
G02X309592Y178100I-1380J1379D01*
G01X307711D01*
G03X306331Y177529I-1J-1951D01*
G01X301023Y172221D01*
G02X300492Y172000I-532J529D01*
G01X288710D01*
G02X288179Y172221I1J750D01*
G01X284203Y176197D01*
G03X282823Y176768I-1379J-1380D01*
G01X282354D01*
G02X281956Y176933I0J563D01*
G01X281902Y176987D01*
G03X281504Y177152I-398J-398D01*
G01X276986D01*
G01X316800Y196500D02*
X315404Y197896D01*
G03X314188Y198400I-1216J-1215D01*
G01X292315D01*
G03X290749Y197751I0J-2214D01*
G01X288903Y195905D01*
G03X287900Y193483I2423J-2422D01*
G01Y186960D01*
G02X286240Y185300I-1660J0D01*
G01X285662D01*
G03X285385Y185185I0J-391D01*
G01X284500Y184300D01*
G01D02*
X284020Y184780D01*
G03X283070Y185243I-1146J-1146D01*
G02X281732Y186388I192J1579D01*
G03X281341Y187060I-1467J-404D01*
G01X281240Y187161D01*
G03X280713Y187379I-526J-526D01*
G01X280585D01*
G03X280298Y187260I0J-406D01*
G01X280199Y187161D01*
G02X279800Y186995I-400J398D01*
G01X276986D01*
G01X316800Y201500D02*
X315403Y200103D01*
G02X314189Y199600I-1214J1214D01*
G01X292315D01*
G03X289900Y198600I-1J-3414D01*
G01X288054Y196754D01*
G03X286700Y193483I3272J-3270D01*
G01Y186960D01*
G02X286240Y186500I-460J0D01*
G01X285690D01*
G02X285366Y186634I0J459D01*
G01X284500Y187500D01*
G01D02*
X283572Y186572D01*
G02X283198Y186442I-321J320D01*
G01X283197D01*
X283196Y186441D01*
Y186438D01*
G02X282888Y186713I66J384D01*
G03X282190Y187909I-2622J-729D01*
G01X282089Y188010D01*
G03X280719Y188579I-1374J-1375D01*
G02X280320Y188744I0J565D01*
G01X280266Y188798D01*
G03X279868Y188963I-398J-398D01*
G01X276986D01*
G01X283400Y198700D02*
X283066Y198365D01*
G03X282500Y197001I1365J-1366D01*
G01X282501Y196063D01*
G03X282586Y195821I390J1D01*
G01X282905Y195422D01*
G02X283601Y193800I-1482J-1596D01*
G01X283600D01*
Y193098D01*
G02X281818Y191316I-1782J0D01*
G01X281350D01*
G03X280952Y191151I0J-563D01*
G01X280898Y191097D01*
G02X280500Y190932I-398J398D01*
G01X276986D01*
G01X280200Y198700D02*
X280876Y198025D01*
G02X281300Y197000I-1025J-1024D01*
G01X281301Y196061D01*
G03X281647Y195073I1590J2D01*
G01X282033Y194589D01*
G02X282400Y193800I-610J-764D01*
G01Y193098D01*
G02X281818Y192516I-582J0D01*
G01X281518D01*
G02X281120Y192681I0J563D01*
G01X281066Y192735D01*
G03X280668Y192900I-398J-398D01*
G01X276986D01*
G01X283400Y198700D02*
X283149Y198952D01*
G02X282300Y201000I2048J2049D01*
G01Y203334D01*
G02X282700Y204300I1366J0D01*
G01X284250Y205849D01*
G02X289200Y207900I4951J-4950D01*
G01X314188D01*
G02X315404Y207396I0J-1719D01*
G01X316800Y206000D01*
G01X280200Y198700D02*
G03X281100Y200873I-2173J2173D01*
G01Y203333D01*
G02X281851Y205149I2566J2D01*
G01X283401Y206698D01*
G02X289199Y209100I5799J-5799D01*
G01X314189D01*
G03X315403Y209603I0J1717D01*
G01X316800Y211000D01*
G01X316500Y175000D02*
X317897Y176397D01*
G02X319111Y176900I1214J-1214D01*
G01X324591D01*
G02X325122Y176680I0J-751D01*
G01X325580Y176222D01*
G02X325800Y175691I-531J-531D01*
G01Y122810D01*
G03X326372Y121430I1951J0D01*
G01X329930Y117872D01*
G03X331310Y117300I1380J1379D01*
G01X335661D01*
G02X336923Y116777I0J-1784D01*
G01X337500Y116200D01*
G01X316500Y180000D02*
X317897Y178603D01*
G03X319111Y178100I1214J1214D01*
G01X324591D01*
G02X325971Y177529I1J-1951D01*
G01X326429Y177071D01*
G02X327000Y175691I-1380J-1379D01*
G01Y122810D01*
G03X327221Y122279I750J1D01*
G01X330779Y118721D01*
G03X331310Y118500I532J529D01*
G01X336000D01*
G03X337022Y118923I0J1446D01*
G01X337499Y119400D01*
X337500D01*
G01X325900Y196900D02*
X325072Y197728D01*
G03X323692Y198300I-1380J-1379D01*
G01X323608D01*
G03X322228Y197728I0J-1951D01*
G01X321000Y196500D01*
G01X325900Y201100D02*
X324733Y199933D01*
G02X323689Y199500I-1045J1044D01*
G01X323611D01*
G02X322567Y199933I1J1477D01*
G01X321000Y201500D01*
G01X325900Y206400D02*
X325072Y207228D01*
G03X323692Y207800I-1380J-1379D01*
G01X323608D01*
G03X322228Y207228I0J-1951D01*
G01X321000Y206000D01*
G01X325900Y210600D02*
X324733Y209433D01*
G02X323689Y209000I-1045J1044D01*
G01X323611D01*
G02X322567Y209433I1J1477D01*
G01X321000Y211000D01*
G01X325900Y196900D02*
X326354Y197353D01*
G02X328879Y198400I2527J-2526D01*
G01X330000D01*
G02X331606Y196794I0J-1606D01*
G01Y132555D01*
G03X332072Y131427I1591J-3D01*
G01X333345Y130154D01*
G02Y129830I-162J-162D01*
G01X333344Y129829D01*
G03Y129505I162J-162D01*
G01X334124Y128726D01*
G03X334448I162J162D01*
G01X334449Y128727D01*
G02X334773I162J-162D01*
G01X335553Y127948D01*
G02Y127624I-162J-162D01*
G01X335552Y127623D01*
G03Y127299I162J-162D01*
G01X336332Y126520D01*
G03X336656I162J162D01*
G01X336657Y126521D01*
G02X336981I162J-162D01*
G01X342580Y120920D01*
G02X342800Y120389I-531J-531D01*
G01Y118406D01*
G02X342580Y118186I-220J0D01*
G03X342360Y117966I0J-220D01*
G01Y116846D01*
G03X342580Y116626I220J0D01*
G02X342800Y116406I0J-220D01*
G01Y110170D01*
G02X342327Y109028I-1615J0D01*
G01X341799Y108500D01*
G01X325900Y201100D02*
X326354Y200647D01*
G03X328880Y199600I2527J2526D01*
G01X330000D01*
G02X332806Y196794I0J-2806D01*
G01Y132554D01*
G03X332921Y132277I390J0D01*
G01X343429Y121769D01*
G02X344000Y120389I-1380J-1379D01*
G01Y110169D01*
G03X344473Y109027I1615J0D01*
G01X344999Y108501D01*
Y108500D01*
G01X325900Y206400D02*
X326268Y206769D01*
G02X329000Y207900I2731J-2732D01*
G01X333000D01*
G02X335500Y205400I0J-2500D01*
G01Y136308D01*
G03X336991Y132709I5089J0D01*
G01X352155Y117545D01*
G02X352300Y117194I-352J-351D01*
G01Y106096D01*
G02X351909Y105152I-1335J0D01*
G01X351464Y104707D01*
G01X325900Y210600D02*
X326268Y210231D01*
G03X329000Y209100I2731J2732D01*
G01X333000D01*
G02X336700Y205400I0J-3700D01*
G01Y136308D01*
G03X337840Y133558I3889J1D01*
G01X353005Y118394D01*
G02X353500Y117194I-1202J-1198D01*
G01Y106657D01*
G03X354055Y105317I1895J0D01*
G01X354664Y104708D01*
Y104707D01*
G01X389161Y144973D02*
X387193Y143005D01*
G01X393098Y144973D02*
X391130Y143005D01*
G01X389161Y152847D02*
X387193Y150879D01*
G01X393098Y152847D02*
X391130Y150879D01*
G01X389161Y160721D02*
X387193Y158753D01*
G01X393098Y160721D02*
X391130Y158753D01*
G01X389161Y168595D02*
X387193Y166627D01*
G01X393098Y168595D02*
X391130Y166627D01*
G01X398000Y89783D02*
X402000D01*
G03X402454Y90237I0J454D01*
G01Y94338D01*
G03X401882Y95718I-1951J0D01*
G01X400600Y97000D01*
G01X408000Y89783D02*
X404500D01*
G02X403654Y90629I0J846D01*
G01Y93946D01*
G02X404226Y95326I1951J0D01*
G01X405900Y97000D01*
G01X401650Y116099D02*
G02X402600Y113805I-2294J-2294D01*
G01Y109508D01*
G02X402028Y108128I-1951J0D01*
G01X401000Y107100D01*
G01X404850Y116099D02*
G03X403800Y113564I2535J-2535D01*
G01Y109586D01*
G03X404356Y108244I1898J0D01*
G01X405500Y107100D01*
G01X400600Y97000D02*
X401828Y98228D01*
G03X402400Y99608I-1379J1380D01*
G01Y100692D01*
G03X401828Y102072I-1951J0D01*
G01X401000Y102900D01*
G01X405900Y97000D02*
X404572Y98328D01*
G02X404000Y99708I1379J1380D01*
G01Y100592D01*
G02X404572Y101972I1951J0D01*
G01X405500Y102900D01*
G01X397035Y148910D02*
X395067Y146942D01*
G01X400973Y148910D02*
X399005Y146942D01*
G01X397035Y156784D02*
X395067Y154816D01*
G01X400973Y156784D02*
X399005Y154816D01*
G01X397035Y164658D02*
X395067Y162690D01*
G01X400973Y164658D02*
X399005Y162690D01*
G01X404910Y152847D02*
X402942Y150879D01*
G01X408847Y152847D02*
X406879Y150879D01*
G01X397035Y172532D02*
X395067Y170564D01*
G01X400973Y172532D02*
X399005Y170564D01*
G01X404910Y168595D02*
X402942Y166627D01*
G01X408847Y168595D02*
X406879Y166627D01*
G01X436400Y90634D02*
Y91056D01*
G02X436644Y91644I832J-1D01*
G01X437928Y92928D01*
G03X438330Y93513I-1380J1379D01*
G02Y93561I2630J24D01*
G01Y95121D01*
G03X438154Y95546I-601J0D01*
G01X436400Y97300D01*
G01X441400Y90634D02*
Y90906D01*
G03X441262Y91238I-470J-1D01*
G01X439949Y92551D01*
G02X439530Y93562I1011J1011D01*
G01Y94405D01*
G02X439972Y95472I1509J0D01*
G01X441800Y97300D01*
G01X436650Y112300D02*
X438385Y110564D01*
G02X438560Y110143I-421J-422D01*
G01Y109208D01*
G02X438385Y108784I-599J-1D01*
G01X438125Y108525D01*
X436900Y107300D01*
G01X441400D02*
X440135Y108565D01*
X439950Y108751D01*
G02X439760Y109208I457J458D01*
G01Y110143D01*
G02X439949Y110599I645J0D01*
G01X441650Y112300D01*
G01X436400Y97300D02*
X437978Y98878D01*
G03X438550Y100258I-1379J1380D01*
G01Y100642D01*
G03X437978Y102022I-1951J0D01*
G01X436900Y103100D01*
G01X441800Y97300D02*
X440093Y99007D01*
G02X439750Y99835I828J828D01*
G01Y100642D01*
G02X440322Y102022I1951J0D01*
G01X441400Y103100D01*
G01X436650Y112300D02*
X438485Y114135D01*
G03X438600Y114412I-276J277D01*
G01Y115360D01*
G03X438396Y115853I-698J0D01*
G01X437650Y116599D01*
G01X441650Y112300D02*
X440004Y113946D01*
G02X439800Y114439I494J493D01*
G01Y115387D01*
G02X439915Y115664I391J0D01*
G01X440850Y116599D01*
G01X444280Y144973D02*
X446248Y143005D01*
G01X457330Y122167D02*
X456415Y121252D01*
G03X456300Y120975I276J-277D01*
G01Y120573D01*
G03X456493Y120107I659J0D01*
G01X458500Y118100D01*
G01X454130Y122167D02*
X454911Y121386D01*
G02X455100Y120930I-456J-456D01*
G01Y120586D01*
G02X454827Y119927I-932J0D01*
G01X453000Y118100D01*
G01X460028Y133161D02*
X461996Y131193D01*
G01X448217Y144973D02*
X450185Y143005D01*
G01X463965Y133161D02*
X465933Y131193D01*
G01X471839Y137098D02*
X473807Y135130D01*
G01X471839Y141035D02*
X473807Y139067D01*
G01X471839Y148910D02*
X473807Y146942D01*
G01X467902Y148910D02*
X469870Y146942D01*
G54D112*
X599450Y127063D03*
Y137063D03*
Y147063D03*
Y157063D03*
Y167063D03*
Y177063D03*
G54D103*
X559700Y173072D03*
Y194529D03*
G54D121*
X641050Y216142D03*
Y213583D03*
Y211024D03*
Y208465D03*
Y205906D03*
G54D10*
G01X315900Y252400D02*
Y247900D01*
G01Y252400D02*
Y256900D01*
G01Y252400D02*
X311600D01*
G01X500400Y259400D02*
X496000D01*
G01X602900Y222500D02*
Y227000D01*
G01X603300Y232400D02*
Y227400D01*
X602900Y227000D01*
G01X607100D02*
X610500D01*
G01X607100Y222500D02*
X612500D01*
X614100Y224100D01*
G01Y227800D02*
Y224100D01*
G01Y236400D02*
Y232200D01*
X614000Y232100D01*
G01X614100Y232000D02*
X614000Y232100D01*
G01D02*
X613700Y232400D01*
X608700D01*
X8878Y21717D03*
X4878D03*
X4000Y25619D03*
Y29619D03*
Y33619D03*
Y37619D03*
Y41619D03*
Y45619D03*
Y49619D03*
Y281619D03*
Y285619D03*
Y289619D03*
Y293619D03*
Y297619D03*
Y301619D03*
Y305619D03*
Y309619D03*
Y313619D03*
Y337619D03*
Y341619D03*
Y345619D03*
Y349619D03*
Y353619D03*
Y357619D03*
Y361619D03*
Y365619D03*
Y369619D03*
Y373619D03*
Y377619D03*
Y381619D03*
Y385619D03*
Y389619D03*
Y393619D03*
Y397619D03*
Y401619D03*
Y405619D03*
Y409619D03*
Y413619D03*
Y417619D03*
Y421619D03*
Y425619D03*
Y429619D03*
X4413Y433598D03*
X8413D03*
X24878Y21717D03*
X20878D03*
X16878D03*
X12878D03*
X12413Y433598D03*
X16413D03*
X20413D03*
X24413D03*
X28413D03*
X44878Y21717D03*
X40878D03*
X36878D03*
X32878D03*
X28878D03*
X46000Y82000D03*
X32413Y433598D03*
X36413D03*
X40413D03*
X44413D03*
X55055Y25073D03*
X52878Y21717D03*
X48878D03*
X55055Y41073D03*
Y37073D03*
Y33073D03*
Y29073D03*
X61463Y54048D03*
X57859Y52313D03*
X55558Y49041D03*
X55055Y45073D03*
X51765Y96600D03*
X48413Y433598D03*
X52413D03*
X56413D03*
X60413D03*
X77460Y54197D03*
X73460D03*
X69460D03*
X65460D03*
X76100Y154400D03*
X75950Y164200D03*
X79500Y234500D03*
X79600Y248900D03*
X79248Y266100D03*
X77964Y260100D03*
X73600Y252500D03*
X75800Y274300D03*
X67000Y283100D03*
X72000Y271400D03*
X68600Y274000D03*
X75500Y282500D03*
X63800Y274000D03*
X76700Y357500D03*
X67100D03*
X73500D03*
X70300D03*
X70500Y419000D03*
X75580Y419004D03*
X68413Y433598D03*
X72413D03*
X76413D03*
X80413D03*
X64413D03*
X97460Y54197D03*
X93460D03*
X89460D03*
X85460D03*
X81460D03*
X88300Y163900D03*
X86800Y230000D03*
X82500Y230500D03*
X84600Y248900D03*
X89600D03*
X85600Y263700D03*
X82500Y273200D03*
X87100Y271300D03*
X85800Y287452D03*
X98000Y420000D03*
X90000Y420500D03*
X85500D03*
X84413Y433598D03*
X88413D03*
X92413D03*
X96413D03*
X113460Y54197D03*
X109460D03*
X105460D03*
X101460D03*
X112800Y66600D03*
X112880Y73020D03*
X113700Y382500D03*
X104100D03*
X110500D03*
X107300D03*
X104413Y433598D03*
X108413D03*
X112413D03*
X100413D03*
X132920Y51926D03*
X129450Y53917D03*
X125460Y54197D03*
X121460D03*
X117460D03*
X126000Y67000D03*
Y62000D03*
X131500Y290500D03*
X116413Y433598D03*
X120413D03*
X124413D03*
X128413D03*
X132413D03*
X135299Y24509D03*
X150163Y21717D03*
X146163D03*
X142163D03*
X138163D03*
X135299Y28509D03*
Y32509D03*
Y36509D03*
Y40509D03*
Y44509D03*
X134977Y48496D03*
X148500Y62500D03*
X139500D03*
X144000D03*
X138500Y75000D03*
X145900Y75200D03*
X142070Y77900D03*
X142000Y69535D03*
X136000Y290500D03*
X138250Y372250D03*
X148500Y376000D03*
X138500Y387500D03*
X140413Y433598D03*
X144413D03*
X148413D03*
X136413D03*
X158163Y21717D03*
X154163D03*
X158795Y25667D03*
Y41667D03*
Y37667D03*
Y33667D03*
Y29667D03*
X160736Y49309D03*
X159112Y45654D03*
X163543Y52159D03*
X151840Y79935D03*
X153500Y390500D03*
X163300Y382900D03*
X151100Y386300D03*
X167100Y405600D03*
X152100Y399300D03*
X151530Y406300D03*
X153150Y394590D03*
X160600Y417400D03*
X152200Y416300D03*
X152413Y433598D03*
X156413D03*
X160413D03*
X164413D03*
X183170Y56390D03*
X180341Y47225D03*
X178196Y50601D03*
X180620Y77890D03*
X180390Y70720D03*
X180910Y63390D03*
X168413Y433598D03*
X172413D03*
X176413D03*
X180413D03*
X184413D03*
X191535Y28900D03*
X201950Y29050D03*
X187598Y36900D03*
X189500Y33000D03*
X186000D03*
X187598Y28900D03*
X191535Y41200D03*
X198135Y36500D03*
X195000Y54550D03*
X203000Y75000D03*
X196497Y76502D03*
X200413Y433598D03*
X188413D03*
X192413D03*
X196413D03*
X210500Y30500D03*
X207880Y78740D03*
X214810Y78810D03*
X208300Y289500D03*
X217300D03*
X212800D03*
X218500Y301700D03*
X213500D03*
X208500D03*
X209660Y331500D03*
X204413Y433598D03*
X208413D03*
X212413D03*
X216413D03*
X220413D03*
X232700Y29100D03*
X221800Y289500D03*
X224500Y302000D03*
X222000Y330000D03*
X224413Y433598D03*
X228413D03*
X232413D03*
X236413D03*
X254527Y28900D03*
X244619D03*
X254527Y33900D03*
X243500Y48650D03*
X252700Y44000D03*
X250222Y76300D03*
X247022D03*
X240508D03*
Y66700D03*
X243822Y76300D03*
X253422D03*
X240508Y69900D03*
Y73100D03*
X240413Y433598D03*
X244413D03*
X248413D03*
X252413D03*
X264339Y35300D03*
Y38500D03*
Y32100D03*
X264304Y28900D03*
X272309D03*
X264339Y41700D03*
X263300Y52200D03*
X269907Y76300D03*
X266707D03*
X263507D03*
X256413Y433598D03*
X260413D03*
X264413D03*
X268413D03*
X272413D03*
X280087Y35300D03*
Y38500D03*
Y41700D03*
Y32100D03*
X280052Y28900D03*
X288057D03*
X285055Y76300D03*
X281855D03*
X288255D03*
X273107D03*
X278655D03*
X284500Y181100D03*
Y184300D03*
Y187500D03*
X283400Y198700D03*
X280200D03*
X277000D03*
X286600D03*
X284500Y190700D03*
X286151Y329500D03*
X289600Y330100D03*
X288413Y433598D03*
X284413D03*
X280413D03*
X276413D03*
X295835Y35300D03*
Y38500D03*
Y41700D03*
Y32100D03*
X295800Y28900D03*
X295835Y44900D03*
Y48100D03*
X298726Y43529D03*
Y49471D03*
X307300Y61300D03*
X297700Y335100D03*
X298700Y327000D03*
Y323500D03*
X293200Y329500D03*
X304413Y433598D03*
X300413D03*
X296413D03*
X292413D03*
X307708Y28900D03*
X321402Y54197D03*
X317402D03*
X314763Y85237D03*
X312500Y87500D03*
X310237Y89763D03*
X317025Y82975D03*
X319510Y190299D03*
X322710D03*
X324000Y236000D03*
X318000Y268500D03*
X324300Y254700D03*
X322200Y320500D03*
Y325000D03*
X310600Y330500D03*
Y335000D03*
X322200Y338500D03*
X324413Y433598D03*
X320413D03*
X316413D03*
X312413D03*
X308413D03*
X329402Y54197D03*
X325402D03*
X337402D03*
X341402D03*
X333402D03*
X338599Y108500D03*
X341799D03*
X337500Y113000D03*
Y122600D03*
Y116200D03*
Y119400D03*
X329110Y190299D03*
X325910D03*
X327500Y232000D03*
X332600Y246600D03*
X328500Y238645D03*
X327800Y246800D03*
X334350Y282000D03*
X336500Y295000D03*
X336525Y320500D03*
Y325500D03*
X341500Y338500D03*
Y328500D03*
Y333500D03*
X336525Y330500D03*
X340413Y433598D03*
X336413D03*
X332413D03*
X328413D03*
X345402Y54197D03*
X349402D03*
X353402D03*
X357402D03*
X349000Y82500D03*
X359300Y92000D03*
X348199Y108500D03*
X348264Y104707D03*
X357864D03*
X344999Y108500D03*
X351464Y104707D03*
X354664D03*
X352300Y175000D03*
X345301Y196299D03*
Y186699D03*
Y193099D03*
Y189899D03*
X358400Y182700D03*
X345930Y217000D03*
X342900Y246800D03*
X354850Y276100D03*
X354800Y285600D03*
Y289800D03*
X344000Y295000D03*
X355000Y332500D03*
Y328000D03*
X358250Y340050D03*
X356413Y433598D03*
X352413D03*
X348413D03*
X344413D03*
X369402Y54197D03*
X373402D03*
X377402D03*
X361402D03*
X365402D03*
X373500Y78000D03*
X368900Y92000D03*
X373500Y94000D03*
X365700Y92000D03*
X362500D03*
X365101Y191559D03*
Y188359D03*
Y194759D03*
Y185159D03*
X361124Y349876D03*
X375500Y350500D03*
X376413Y433598D03*
X372413D03*
X368413D03*
X364413D03*
X360413D03*
X381402Y54197D03*
X385402D03*
X389402D03*
X393402D03*
X379500Y72500D03*
X380500Y77400D03*
X380400Y81600D03*
X381700Y92400D03*
X390000Y100500D03*
X387193Y143005D03*
X391130D03*
X387193Y135130D03*
X391130Y139067D03*
X387193D03*
Y146942D03*
X391130D03*
Y135130D03*
X387193Y150879D03*
X391130D03*
X387193Y158753D03*
X391130D03*
X387193Y154816D03*
Y162690D03*
X391130D03*
Y154816D03*
X387193Y166627D03*
X391130D03*
X387193Y170564D03*
X391130Y178437D03*
X387193D03*
X391130Y170564D03*
X383128Y178372D03*
X391130Y182374D03*
Y186311D03*
X385500Y196154D03*
X387193Y186311D03*
X391130Y205996D03*
Y209933D03*
X387193D03*
Y217807D03*
X391600Y304800D03*
X379300Y305000D03*
X383000Y328500D03*
Y333500D03*
Y346600D03*
X388500Y391000D03*
X393500D03*
X388500Y400000D03*
X393500D03*
X393000Y418500D03*
X392413Y433598D03*
X388413D03*
X384413D03*
X380413D03*
X397402Y54197D03*
X401402D03*
X405402D03*
X409402D03*
X396400Y100500D03*
X409200D03*
X398450Y116099D03*
X408050D03*
X401650D03*
X404850D03*
X395067Y146942D03*
X399005D03*
X395067Y139067D03*
X399005D03*
Y143005D03*
X402942D03*
Y146942D03*
X406879D03*
X410816D03*
X395067Y143005D03*
Y131193D03*
X406879Y135130D03*
X410816D03*
X406879Y139067D03*
X402942D03*
X410811Y131188D03*
X406874D03*
X399000Y135125D03*
Y131188D03*
X395067Y135130D03*
X410816Y143005D03*
Y139067D03*
X406879Y143005D03*
X395067Y154816D03*
X399005D03*
X395067Y162690D03*
X399005D03*
X395067Y150879D03*
X402942Y154816D03*
X399005Y158753D03*
X410816D03*
X402942Y162690D03*
X410816D03*
Y150879D03*
Y154816D03*
X395067Y158753D03*
X402942Y150879D03*
X406879D03*
X399005D03*
X402942Y158753D03*
X406879Y162690D03*
Y154816D03*
Y158753D03*
X395067Y170564D03*
X399005D03*
X395067Y166627D03*
X410816D03*
X402942Y170564D03*
X406879D03*
X395067Y178437D03*
X399005D03*
X410816D03*
Y170564D03*
X402942Y166627D03*
X406879D03*
X399005D03*
X402942Y178437D03*
X406879D03*
X395067Y182374D03*
X399005Y186311D03*
Y190248D03*
X406879Y198122D03*
X399005Y182374D03*
X410816Y186311D03*
X395067Y194185D03*
X402942Y190248D03*
X406879Y182374D03*
Y186311D03*
Y194185D03*
X395067Y186311D03*
Y190248D03*
X402942Y182374D03*
X399005Y198122D03*
X395067D03*
X410816Y182374D03*
Y190248D03*
Y198122D03*
X402942Y186311D03*
Y194185D03*
X399005D03*
X402942Y198122D03*
X410816Y194185D03*
X406879Y190248D03*
X402942Y209933D03*
X395067Y213870D03*
X410816Y205996D03*
X399005Y202059D03*
X395067D03*
X402942Y205996D03*
X399005D03*
X406879Y202059D03*
X410816Y209933D03*
Y202059D03*
X399005Y209933D03*
X395067D03*
X406879Y205996D03*
Y209933D03*
X402942Y202059D03*
X395067Y205996D03*
X406879Y213870D03*
Y217807D03*
X405463Y383000D03*
X410463D03*
X398500Y391000D03*
Y400000D03*
X403000Y418500D03*
X398000D03*
X408413Y433598D03*
X404413D03*
X400413D03*
X396413D03*
X417402Y54197D03*
X421402D03*
X425402D03*
X429402D03*
X413402D03*
X413622Y75000D03*
X414753Y131193D03*
X422627Y146942D03*
X426564Y135130D03*
X418690Y139067D03*
X422627Y135130D03*
X418690D03*
X414753D03*
X422627Y131193D03*
X418690D03*
X426564Y146942D03*
Y143005D03*
Y131193D03*
Y139067D03*
X422627D03*
Y143005D03*
X418690D03*
X414753D03*
Y139067D03*
X418690Y146942D03*
X414753D03*
Y162690D03*
Y154816D03*
X418690Y158753D03*
X422627Y162690D03*
Y154816D03*
X426564Y162690D03*
Y158753D03*
X418690Y154816D03*
Y162690D03*
X414753Y158753D03*
X422627D03*
X426564Y154816D03*
X414753Y150879D03*
X422627D03*
X418690D03*
X426564D03*
X418690Y166627D03*
X414753Y170564D03*
X422627D03*
X418690Y178437D03*
X426564Y166627D03*
Y178437D03*
X418690Y170564D03*
X414753Y166627D03*
X426564Y170564D03*
X414753Y178437D03*
X422627Y166627D03*
Y178437D03*
Y190248D03*
X414753Y194185D03*
X426564Y198122D03*
X418690Y182374D03*
X426564Y186311D03*
Y190248D03*
X418690Y198122D03*
X422627Y194185D03*
Y186311D03*
Y182374D03*
X426564D03*
X414753Y190248D03*
X418690D03*
Y186311D03*
X414753D03*
Y182374D03*
Y198122D03*
X426564Y194185D03*
X422627Y198122D03*
X418690Y194185D03*
X414753Y213870D03*
X418690Y202059D03*
X422627Y209933D03*
X418690Y205996D03*
X414753D03*
Y209933D03*
X418690Y213870D03*
X414753Y202059D03*
X426564D03*
Y205996D03*
Y209933D03*
X422627Y202059D03*
Y205996D03*
X418690Y209933D03*
X426564Y217807D03*
X421360Y359970D03*
X415463Y383000D03*
X414000Y419000D03*
X422337Y424000D03*
X416800D03*
X428413Y433598D03*
X424413D03*
X420413D03*
X416413D03*
X412413D03*
X433402Y54197D03*
X437402D03*
X441402D03*
X445402D03*
X444050Y116599D03*
X434450D03*
X437650D03*
X440850D03*
X442311Y139067D03*
X446248Y143005D03*
X434437D03*
X438374Y131193D03*
X446248Y146942D03*
X442311Y143005D03*
Y146942D03*
X438374Y135130D03*
X434437Y146942D03*
X438374D03*
X446248Y139067D03*
X445939Y135439D03*
X438374Y143005D03*
Y139067D03*
X434437D03*
Y135130D03*
Y131193D03*
X446248Y158753D03*
X442311Y162690D03*
X434437D03*
Y154816D03*
X438374Y162690D03*
Y150879D03*
Y158753D03*
X442311Y154816D03*
X434437Y158753D03*
X442311D03*
X438374Y154816D03*
X446248D03*
Y162690D03*
X434437Y150879D03*
X442311D03*
X446248D03*
X438374Y166627D03*
X446248D03*
X434437Y170564D03*
X442311D03*
X446248Y178437D03*
X434437Y166627D03*
X438374Y178437D03*
Y170564D03*
X442311Y166627D03*
X434437Y178437D03*
X446248Y170564D03*
X442311Y178437D03*
X446248Y182374D03*
Y186311D03*
X442311D03*
Y182374D03*
X438374Y194185D03*
Y190248D03*
X446248D03*
X434437Y186311D03*
Y190248D03*
Y194185D03*
Y182374D03*
X438374Y198122D03*
X442311Y190248D03*
Y194185D03*
X434437Y198122D03*
X446248D03*
X438374Y182374D03*
Y186311D03*
X446248Y194185D03*
X442311Y198122D03*
X434437Y205996D03*
X446248Y209933D03*
X438374D03*
Y205996D03*
Y202059D03*
X442311Y209933D03*
X438374Y213870D03*
X442311Y202059D03*
X434437D03*
Y213870D03*
X442311Y205996D03*
X446248D03*
Y202059D03*
X434437Y209933D03*
X438374Y217807D03*
X434437D03*
X446500Y289500D03*
X441500Y297500D03*
X439500Y337892D03*
X442500Y336089D03*
X439500Y341500D03*
X443000Y386500D03*
Y401500D03*
Y396500D03*
X432000D03*
X444000Y406500D03*
X431900Y392200D03*
X431169Y401169D03*
X444000Y416500D03*
Y411500D03*
X444413Y433598D03*
X440413D03*
X436413D03*
X432413D03*
X449402Y54197D03*
X453402D03*
X457402D03*
X461402D03*
X450930Y122167D03*
X460530D03*
X457330D03*
X454130D03*
X454122Y143005D03*
X457844Y131408D03*
X461996Y131193D03*
X450185Y143005D03*
Y135130D03*
X461996Y139067D03*
X454122D03*
X458059D03*
X461996Y135130D03*
X454122D03*
X457844Y135345D03*
X449876Y131502D03*
X454122Y131193D03*
X458059Y146942D03*
X461996D03*
X450185D03*
X454122D03*
X458059Y143005D03*
X461996D03*
X450185Y139067D03*
X458059Y158753D03*
X450185Y154816D03*
X461996Y158753D03*
X450185Y162690D03*
X454122Y158753D03*
Y162690D03*
X450185Y158753D03*
X458059Y150879D03*
Y162690D03*
X454122Y150879D03*
X461996D03*
X454122Y154816D03*
X458059D03*
X461996D03*
X450185Y150879D03*
X458059Y178437D03*
Y166627D03*
X450185Y170564D03*
X454123D03*
X454122Y166627D03*
X450185D03*
Y178437D03*
X454122D03*
X461996Y170564D03*
Y178437D03*
X458060Y170564D03*
X461996Y166627D03*
X450185Y182374D03*
X454122Y186311D03*
X450185Y198122D03*
X458059Y190248D03*
X454122Y182374D03*
X461996D03*
X458059Y194185D03*
X461996Y186311D03*
X458059Y182374D03*
X454122Y194185D03*
X450185D03*
X454122Y190248D03*
X458059Y186311D03*
X454122Y198122D03*
X458059D03*
X461996Y190248D03*
Y198122D03*
Y194185D03*
X450185Y186311D03*
Y190248D03*
X461996Y202059D03*
X458059Y213870D03*
X454122Y205996D03*
X461996Y209933D03*
Y205996D03*
Y213870D03*
X458059Y202059D03*
Y205996D03*
X454122Y209933D03*
X458059D03*
X450185D03*
Y213870D03*
X454122D03*
X450185Y202059D03*
X454122D03*
X450185Y205996D03*
X454122Y217807D03*
X450185D03*
X461996D03*
X458059D03*
X464413Y433598D03*
X460413D03*
X456413D03*
X452413D03*
X448413D03*
X465402Y54197D03*
X469402D03*
X473402D03*
X477402D03*
X481402D03*
X465933Y146942D03*
X469870Y135130D03*
X465933Y131193D03*
X473807Y135130D03*
Y139067D03*
Y146942D03*
X469870D03*
X473807Y143005D03*
X465933Y139067D03*
X469870D03*
Y131193D03*
X473807D03*
X465933Y135130D03*
Y143005D03*
X469870D03*
X465933Y154816D03*
X469870D03*
X475000Y163000D03*
X465933Y158753D03*
Y150879D03*
X469870D03*
Y178437D03*
X473807Y166627D03*
X465933D03*
Y170564D03*
Y178437D03*
X469870Y166627D03*
Y170564D03*
X473807D03*
Y178437D03*
X465933Y190248D03*
Y194185D03*
X473807Y186311D03*
X469870Y198122D03*
X465933Y186311D03*
X469870Y190248D03*
X473807Y182374D03*
X469870D03*
X465933D03*
X469870Y186311D03*
X473807Y190248D03*
X469870Y194185D03*
X465933Y198122D03*
X473807Y205996D03*
X465933Y209933D03*
X469870Y213870D03*
Y209933D03*
X465933Y202059D03*
Y205996D03*
X473807Y213870D03*
X469870Y205996D03*
X473807Y209933D03*
X469870Y217807D03*
X473807D03*
X470462Y369462D03*
X470500Y395000D03*
X480413Y433598D03*
X476413D03*
X472413D03*
X468413D03*
X485402Y54197D03*
X489402D03*
X493402D03*
X497402D03*
X490970Y133500D03*
Y138500D03*
X488500Y359000D03*
X493500D03*
X496413Y433598D03*
X492413D03*
X488413D03*
X484413D03*
X501402Y54197D03*
X505402D03*
X509402D03*
X513402D03*
X500500Y271100D03*
X500000Y278799D03*
X503000Y354600D03*
X516413Y433598D03*
X512413D03*
X508413D03*
X504413D03*
X500413D03*
X517402Y54197D03*
X521402D03*
X525402D03*
X529402D03*
X533402D03*
X533000Y95000D03*
Y99500D03*
X522400Y270700D03*
X522600Y276200D03*
X528500Y299000D03*
X532300Y425700D03*
X532413Y433598D03*
X528413D03*
X524413D03*
X520413D03*
X537402Y54197D03*
X541402D03*
X545402D03*
X549402D03*
X549500Y69400D03*
X548158Y228033D03*
X545250Y256300D03*
X539977Y275124D03*
X540318Y270436D03*
X537500Y296607D03*
X550643Y400900D03*
X548413Y433598D03*
X544413D03*
X540413D03*
X536413D03*
X553402Y54197D03*
X557402D03*
X561402D03*
X565402D03*
X568600Y76000D03*
X566600Y212900D03*
X553122Y227979D03*
X559500Y228000D03*
X566700Y227500D03*
X568000Y356700D03*
X552000Y367597D03*
Y371141D03*
X555200Y367597D03*
Y371141D03*
X555569Y388051D03*
X552000Y374684D03*
Y378227D03*
X555200D03*
Y374684D03*
X568413Y433598D03*
X564413D03*
X560413D03*
X556413D03*
X552413D03*
X569402Y54197D03*
X573402D03*
X577402D03*
X581402D03*
X585402D03*
X572500Y60301D03*
X572870Y67570D03*
X577100Y227900D03*
X581400Y262100D03*
Y272100D03*
Y282100D03*
X581500Y302100D03*
X576200Y342500D03*
X584413Y433598D03*
X580413D03*
X576413D03*
X572413D03*
X589402Y54197D03*
X593402D03*
X597402D03*
X601402D03*
X597000Y199900D03*
X591902Y200300D03*
X601902Y200100D03*
X594153Y220500D03*
X589953Y236600D03*
X591000Y261500D03*
X590500Y301500D03*
X600413Y433598D03*
X596413D03*
X592413D03*
X588413D03*
X605402Y54197D03*
X609402D03*
X613402D03*
X617402D03*
X621402D03*
X606902Y200400D03*
X619961Y230874D03*
Y221274D03*
Y224474D03*
Y227674D03*
X620413Y433598D03*
X616413D03*
X612413D03*
X608413D03*
X604413D03*
X625402Y54197D03*
X629402D03*
X633500Y205906D03*
X625800Y215874D03*
X633000Y267000D03*
X636413Y433598D03*
X632413D03*
X628413D03*
X624413D03*
X649402Y54197D03*
X653402D03*
X656039Y57205D03*
Y61205D03*
Y65205D03*
Y69205D03*
Y73205D03*
Y77205D03*
Y81205D03*
Y85205D03*
Y89205D03*
Y93205D03*
Y97205D03*
Y101205D03*
Y105205D03*
Y109205D03*
Y113205D03*
Y117205D03*
Y121205D03*
Y125205D03*
Y129205D03*
Y145205D03*
Y133205D03*
Y137205D03*
Y141205D03*
Y149205D03*
Y153205D03*
Y157205D03*
Y161205D03*
Y165205D03*
Y169205D03*
Y173205D03*
Y177205D03*
Y181205D03*
Y235585D03*
Y311909D03*
Y315909D03*
Y319909D03*
Y323909D03*
Y327909D03*
Y331909D03*
Y335909D03*
Y339909D03*
Y343909D03*
Y347909D03*
Y351909D03*
Y355909D03*
Y359909D03*
Y363909D03*
Y367909D03*
Y371909D03*
Y375909D03*
Y379909D03*
Y383909D03*
Y387909D03*
Y391909D03*
Y395909D03*
Y399909D03*
Y403909D03*
Y407909D03*
Y411909D03*
Y415909D03*
Y419909D03*
Y423909D03*
Y427909D03*
Y431909D03*
X652413Y433598D03*
X648413D03*
X644413D03*
X640413D03*
G54D131*
G01X75740Y350650D02*
Y349898D01*
G02X75133Y348433I-2071J0D01*
G01X74904Y348204D01*
G03X74295Y346734I1470J-1470D01*
G01Y346221D01*
G02X73541Y344403I-2569J0D01*
G02X71361Y343500I-2180J2180D01*
G01X53096D01*
G02X50334Y344644I0J3907D01*
G01X49467Y345511D01*
G03X48288Y346000I-1180J-1178D01*
G01X38660D01*
G03X37760Y345100I0J-900D01*
G01Y344409D01*
G03X37927Y344005I572J0D01*
G01X38782Y343150D01*
G01X35238D02*
X36092Y344005D01*
G03X36260Y344409I-404J405D01*
G01Y345100D01*
G02X38660Y347500I2400J0D01*
G01X48288D01*
G02X50528Y346572I0J-3167D01*
G01X51395Y345705D01*
G03X53097Y345000I1702J1702D01*
G01X54499D01*
G03X54949Y345450I0J450D01*
G02X55399Y345900I450J0D01*
G01X56779D01*
G02X57229Y345450I0J-450D01*
G03X57679Y345000I450J0D01*
G01X59059D01*
G03X59509Y345450I0J450D01*
G02X59959Y345900I450J0D01*
G01X61339D01*
G02X61789Y345450I0J-450D01*
G03X62239Y345000I450J0D01*
G01X63619D01*
G03X64069Y345450I0J450D01*
G02X64519Y345900I450J0D01*
G01X65899D01*
G02X66349Y345450I0J-450D01*
G03X66799Y345000I450J0D01*
G01X68805D01*
G03X69650Y345845I0J845D01*
G01Y346199D01*
G03X69473Y346627I-606J0D01*
G01X69073Y347027D01*
G02X68260Y348990I1963J1963D01*
G01Y350650D01*
G01X73500Y357500D02*
X73227Y357227D01*
G03X72600Y355714I1512J-1513D01*
G03X73814Y354500I1214J0D01*
G01X74399D01*
G02X75042Y354234I0J-909D01*
G01X75133Y354143D01*
G02X75740Y352678I-1464J-1465D01*
G01Y350650D01*
G01X70300Y357500D02*
X70933Y356867D01*
G02X71100Y356463I-405J-404D01*
G01Y355500D01*
G02X70938Y355109I-553J0D01*
G01X70711Y354882D01*
X70379Y354682D01*
G02X70083Y354600I-296J492D01*
G01X69629Y354574D01*
G03X68656Y354116I147J-1576D01*
G03X68260Y353159I948J-953D01*
G01Y350650D01*
G01X115253Y357800D02*
Y361283D01*
G03X115086Y361686I-570J0D01*
G01X115060Y361712D01*
G02X114980Y361812I402J404D01*
G01Y363366D01*
G03X114125Y365535I-3175J2D01*
G01X114078Y365584D01*
X114037Y365629D01*
G02X113900Y365973I368J346D01*
G01Y366666D01*
G02X114348Y367749I1531J1D01*
G01X115500Y368900D01*
G01X113284Y357800D02*
Y361283D01*
G02X113451Y361686I570J0D01*
G01X113476Y361711D01*
G03X113480Y361715I-401J405D01*
G02Y361744I1242J14D01*
G01Y363366D01*
G03X113029Y364509I-1674J0D01*
G01X112940Y364604D01*
G02X112400Y365973I1465J1369D01*
G01Y366666D01*
G03X112383Y366805I-577J0D01*
G03X112108Y367292I-1013J-251D01*
G01X110500Y368900D01*
G01X115500Y373100D02*
X113745Y374856D01*
G03X113075Y376944I-2367J392D01*
G01X109945Y380074D01*
G02X109710Y380643I568J568D01*
G01Y381355D01*
G02X109961Y381961I857J0D01*
G01X110500Y382500D01*
G01Y373100D02*
X112013Y374613D01*
G03Y375883I-635J635D01*
G01X108883Y379013D01*
G02X108210Y380645I1631J1627D01*
G01Y381354D01*
G03X108043Y381757I-570J0D01*
G01X107300Y382500D01*
G01X242716Y13781D02*
Y21806D01*
G03X242280Y22858I-1487J0D01*
G01X242042Y23096D01*
G02X241500Y24405I1310J1309D01*
G01Y31351D01*
G02X242454Y33654I3257J0D01*
G01X246034Y37234D01*
G02X248366Y38200I2332J-2332D01*
G01X250529D01*
G03X256661Y40739I2J8670D01*
G01X258761Y42839D01*
G02X265909Y45800I7148J-7148D01*
G01X294100D01*
G02X295526Y45210I1J-2016D01*
G01X295835Y44900D01*
G01Y48100D02*
X295554Y47820D01*
G02X294300Y47300I-1255J1254D01*
G01X265908D01*
G03X257700Y43900I1J-11609D01*
G01X255600Y41800D01*
G02X250529Y39700I-5070J5070D01*
G01X248366D01*
G03X244973Y38295I-1J-4798D01*
G01X241393Y34715D01*
G03X240000Y31351I3364J-3363D01*
G01Y24441D01*
G02X239437Y23082I-1922J0D01*
G01X239288Y22933D01*
G03X238779Y21705I1227J-1228D01*
G01Y13781D01*
G01X262401D02*
Y21690D01*
G03X261900Y22900I-1711J0D01*
G01X261544Y23256D01*
G02X261182Y24130I874J874D01*
G01Y35187D01*
G02X261487Y35890I963J0D01*
G02X262019Y36100I531J-567D01*
G01X263303D01*
G02X263706Y35933I0J-570D01*
G01X264339Y35300D01*
G01X258464Y13781D02*
Y22171D01*
G02X258672Y22673I710J0D01*
G01X259254Y23255D01*
G03X259682Y24288I-1033J1033D01*
G01Y35187D01*
G02X260461Y36986I2463J1D01*
G02X262020Y37600I1556J-1664D01*
G01X263252D01*
Y37650D01*
G03X263656Y37817I0J571D01*
G01X264339Y38500D01*
G01X278149Y13781D02*
Y21564D01*
G03X277542Y23029I-2071J0D01*
G01X277504Y23067D01*
G02X277000Y24284I1217J1217D01*
G01Y35139D01*
G02X278061Y36200I1061J0D01*
G01X278943D01*
G02X279359Y36027I-1J-589D01*
G01X280087Y35300D01*
G01X274212Y13781D02*
Y21585D01*
G02X274805Y23017I2026J0D01*
G01X275107Y23319D01*
G03X275500Y24267I-947J948D01*
G01Y35139D01*
G02X278061Y37700I2561J0D01*
G01X278994D01*
G03X279494Y37907I0J707D01*
G01X280087Y38500D01*
G01X293897Y13781D02*
Y21564D01*
G03X293290Y23029I-2071J0D01*
G01X293274Y23045D01*
G02X292700Y24431I1386J1386D01*
G01Y35430D01*
G02X293361Y36094I664J0D01*
G01X294516Y36100D01*
X294617D01*
G02X295330Y35804I-1J-1009D01*
G01X295835Y35300D01*
G01X289960Y13781D02*
Y21808D01*
G02X290396Y22860I1487J0D01*
G01X290769Y23233D01*
G03X291200Y24273I-1039J1040D01*
G01Y35430D01*
G02X293353Y37594I2164J0D01*
G01X294512Y37600D01*
X294616D01*
G03X295163Y37827I0J774D01*
G01X295835Y38500D01*
G01X311900Y185000D02*
X311048Y185852D01*
G03X310382Y186336I-1865J-1866D01*
G02X306869Y187139I-1117J3199D01*
G01X303483Y190525D01*
G03X301757Y191240I-1726J-1726D01*
G01X297475D01*
G03X297123Y191119I-1J-570D01*
G02X296584Y190932I-540J685D01*
G01X292734D01*
G01X311900Y189500D02*
X310600Y188200D01*
G02X307930I-1335J1335D01*
G01X304544Y191586D01*
G03X301758Y192740I-2786J-2787D01*
G01X297259D01*
X297099Y192900D01*
X292734D01*
G01X325910Y190299D02*
X325496Y189885D01*
G03X325030Y188760I1125J-1125D01*
G01Y188512D01*
G02X324935Y187949I-1708J-1D01*
G02X322980Y186560I-1955J681D01*
G01X318185D01*
X317950Y186478D01*
G03X316952Y185852I868J-2492D01*
G01X316100Y185000D01*
G01Y189500D02*
X316952Y188648D01*
G03X317849Y188060I1865J1866D01*
G01X322980D01*
G03X323518Y188444I0J569D01*
G01X323530Y188511D01*
Y189117D01*
G03X323274Y189735I-874J0D01*
G01X322710Y190299D01*
G01X358207Y192336D02*
X360336D01*
X360411Y192411D01*
X361160D01*
G03X363230Y194481I0J2070D01*
G01Y200521D01*
G03X362776Y201939I-2432J3D01*
G03X360227Y203778I-4017J-2882D01*
G03X359216Y203930I-1005J-3246D01*
G01X344463D01*
G03X342956Y203541I-4J-3100D01*
G03X340083Y199598I2817J-5070D01*
G03X340000Y198738I4336J-852D01*
G01Y138847D01*
G03X341963Y134107I6702J-1D01*
G01X359949Y116121D01*
G02X363350Y107912I-8208J-8210D01*
G01Y93499D01*
G03X363349Y93455I1942J-66D01*
G01X363350Y93452D01*
G02X362500Y92000I-3207J903D01*
G01X358207Y193911D02*
X361160D01*
G03X361730Y194481I0J570D01*
G01Y200521D01*
G03X361556Y201064I-931J1D01*
G03X359783Y202345I-2799J-2006D01*
G03X359218Y202430I-562J-1813D01*
G01X344462D01*
G03X343685Y202229I-1J-1599D01*
G03X341555Y199307I2088J-3759D01*
G03X341500Y198739I2863J-564D01*
G01Y175015D01*
G03X341895Y174620I395J0D01*
G02X342290Y174225I0J-395D01*
G01Y172735D01*
G02X341895Y172340I-395J0D01*
G03X341500Y171945I0J-395D01*
G01Y170455D01*
G03X341895Y170060I395J0D01*
G02X342290Y169665I0J-395D01*
G01Y168175D01*
G02X341895Y167780I-395J0D01*
G03X341500Y167385I0J-395D01*
G01Y165895D01*
G03X341895Y165500I395J0D01*
G02X342290Y165105I0J-395D01*
G01Y163615D01*
G02X341895Y163220I-395J0D01*
G03X341500Y162825I0J-395D01*
G01Y161335D01*
G03X341895Y160940I395J0D01*
G02X342290Y160545I0J-395D01*
G01Y159055D01*
G02X341895Y158660I-395J0D01*
G03X341500Y158265I0J-395D01*
G01Y156775D01*
G03X341895Y156380I395J0D01*
G02X342290Y155985I0J-395D01*
G01Y154495D01*
G02X341895Y154100I-395J0D01*
G03X341500Y153705I0J-395D01*
G01Y152215D01*
G03X341895Y151820I395J0D01*
G02X342290Y151425I0J-395D01*
G01Y149935D01*
G02X341895Y149540I-395J0D01*
G03X341500Y149145I0J-395D01*
G01Y147655D01*
G03X341895Y147260I395J0D01*
G02X342290Y146865I0J-395D01*
G01Y145375D01*
G02X341895Y144980I-395J0D01*
G03X341500Y144585I0J-395D01*
G01Y138847D01*
G03X343024Y135168I5202J0D01*
G01X361010Y117182D01*
G02X364850Y107912I-9269J-9270D01*
G01Y93491D01*
G03Y93476I443J-7D01*
G01Y93452D01*
G03X365700Y92000I3203J900D01*
G01X358207Y190762D02*
X361149D01*
X361221Y190690D01*
X363442D01*
G03X363671Y190721I2J843D01*
G03X365101Y191559I-889J3155D01*
G01X358207Y189187D02*
X361150D01*
X361153Y189190D01*
X363441D01*
G03X363694Y189203I6J2343D01*
G02X365101Y188359I-983J-3234D01*
G01X345301Y193099D02*
X345466Y192933D01*
G03X346413Y192330I1833J1834D01*
G01X350595D01*
Y192336D01*
G01X345301Y189899D02*
X345638Y190235D01*
G02X346443Y190762I1663J-1662D01*
G01X346616Y190830D01*
X350595D01*
Y190762D01*
G01X623249Y220184D02*
Y223004D01*
G02X624119Y223874I870J0D01*
G01X626650D01*
G03X627220Y224444I0J570D01*
G01Y225279D01*
G03X626670Y225700I-550J-149D01*
G01X621253D01*
X620974Y225487D01*
X619961Y224474D01*
G01X630729Y220184D02*
Y222379D01*
G03X629534Y223574I-1195J0D01*
G02X628720Y224388I0J814D01*
G01Y225417D01*
G03X626670Y227200I-2050J-287D01*
G01X621105D01*
G02X620693Y227253I-1J1618D01*
G01X619961Y227674D01*
G01X623249Y220184D02*
Y215072D01*
G03X623490Y214490I823J0D01*
G01X624473Y213506D01*
X624944Y213033D01*
G02X625110Y212630I-406J-403D01*
G01Y211684D01*
G03X625490Y210345I2542J-2D01*
G03X627993Y208950I2503J1548D01*
G01X636560D01*
G02X636963Y208783I0J-570D01*
G01X637114Y208632D01*
G03X637517Y208465I403J403D01*
G01X641050D01*
G01X630729Y220184D02*
Y216389D01*
G02X630609Y215836I-1328J-1D01*
G02X630198Y215440I-710J326D01*
G01X629625Y215202D01*
G02X628738Y215024I-888J2128D01*
G03X627813Y214641I0J-1309D01*
G01X627009Y213837D01*
G03X626610Y212874I963J-963D01*
G01Y211683D01*
G03X626766Y211134I1042J-1D01*
G03X627993Y210450I1227J759D01*
G01X630914D01*
G03X631214Y210750I0J300D01*
G02X631514Y211050I300J0D01*
G01X633194D01*
G02X633494Y210750I0J-300D01*
G03X633794Y210450I300J0D01*
G01X636560D01*
G02X636677Y210447I5J-2070D01*
G03X636793Y210536I-286J493D01*
G01X637114Y210857D01*
G02X637517Y211024I403J-403D01*
G01X641050D01*
G54D113*
X599000Y209400D03*
G54D122*
X651582Y223623D03*
G54D20*
X28100Y156898D03*
Y152698D03*
X23600Y156898D03*
Y152698D03*
X19100Y156898D03*
Y152698D03*
X24200Y266408D03*
X19700D03*
X24200Y270608D03*
X19700D03*
X18000Y318900D03*
X23000D03*
X28000D03*
X18000Y323100D03*
X23000D03*
X28000D03*
X44300Y64700D03*
Y68900D03*
X45500Y108390D03*
Y112590D03*
Y117800D03*
Y122000D03*
X32600Y156898D03*
Y152698D03*
X37100Y156898D03*
Y152698D03*
X41600Y156898D03*
Y152698D03*
X45500Y164400D03*
Y178100D03*
Y173900D03*
Y168600D03*
X45200Y232600D03*
Y236800D03*
X37700Y266408D03*
X42200D03*
X33200D03*
X28700D03*
X37700Y270608D03*
X42200D03*
X33200D03*
X28700D03*
X43000Y318900D03*
X38000D03*
X33000D03*
X43000Y323100D03*
X38000D03*
X33000D03*
X58000Y88400D03*
Y92600D03*
X48500D03*
Y88400D03*
X53500D03*
Y92600D03*
X62500Y108400D03*
Y112600D03*
X50500Y112590D03*
Y108390D03*
X58000Y144400D03*
X48000D03*
X53000D03*
X60600Y164745D03*
X58000Y148600D03*
X48000D03*
X53000D03*
X60600Y168945D03*
X57500Y204900D03*
Y209100D03*
X48000D03*
Y204900D03*
X53000D03*
Y209100D03*
X51452Y227500D03*
Y223300D03*
X46452D03*
Y227500D03*
X57800Y256900D03*
Y261100D03*
X47800D03*
Y256900D03*
X53000Y258400D03*
Y262600D03*
X59500Y355400D03*
Y359600D03*
X71400Y225200D03*
Y229400D03*
X64000Y222900D03*
Y227100D03*
X71500Y244400D03*
Y240200D03*
X76948Y252500D03*
Y256700D03*
X80648Y283100D03*
Y278900D03*
X83500Y252400D03*
Y256600D03*
X107500Y293900D03*
Y298100D03*
X112500Y293900D03*
Y298100D03*
X102500D03*
Y293900D03*
X110500Y368900D03*
Y373100D03*
X115500Y368900D03*
Y373100D03*
X105500Y368900D03*
Y373100D03*
X117500Y293900D03*
Y298100D03*
X144500Y370400D03*
Y374600D03*
X138500Y408400D03*
Y412600D03*
X154800Y66320D03*
Y62120D03*
X153000Y300400D03*
X151000Y320600D03*
Y316400D03*
X153000Y304600D03*
X155600Y416200D03*
Y412000D03*
X183500Y293900D03*
Y298100D03*
X199770Y59000D03*
Y63200D03*
X188500Y298100D03*
Y293900D03*
X195900Y324700D03*
Y328900D03*
X210500Y59400D03*
X215000D03*
X204770Y59000D03*
X210500Y63600D03*
X215000D03*
X204770Y63200D03*
X217300Y297300D03*
Y293100D03*
X212800Y297300D03*
Y293100D03*
X208300Y297300D03*
Y293100D03*
X217600Y384500D03*
Y388700D03*
X221800Y297300D03*
Y293100D03*
X226280Y328700D03*
Y324500D03*
X251122Y58400D03*
Y62600D03*
X325900Y196900D03*
Y201100D03*
Y206400D03*
Y210600D03*
X338484Y251100D03*
X333500D03*
X328500D03*
X338484Y255300D03*
X333500D03*
X328500D03*
X325500Y370600D03*
Y366400D03*
X357500Y162100D03*
Y157900D03*
X355400Y178749D03*
Y174549D03*
X354600Y251300D03*
X343500Y251100D03*
X354600Y255500D03*
X343500Y255300D03*
X358200Y285600D03*
Y276100D03*
Y280300D03*
Y289800D03*
X344300Y381600D03*
Y385800D03*
X377000Y87400D03*
Y91600D03*
X360400Y174549D03*
Y178749D03*
X370500Y238400D03*
Y242600D03*
X376000D03*
Y238400D03*
X366200Y297600D03*
Y301800D03*
X362300Y387800D03*
Y383600D03*
X391900Y251000D03*
X386000D03*
X380100D03*
X391900Y255200D03*
X386000D03*
X380100D03*
X379700Y284900D03*
Y296900D03*
Y301100D03*
Y289100D03*
X387000Y346600D03*
Y342400D03*
X401000Y107100D03*
Y102900D03*
X405500Y107100D03*
Y102900D03*
X403700Y251000D03*
X397800D03*
X409300D03*
X403700Y255200D03*
X397800D03*
X409300D03*
X408000Y347100D03*
Y342900D03*
X420500Y87900D03*
Y92100D03*
X420900Y251000D03*
X415000D03*
X420900Y255200D03*
X415000D03*
X436900Y107300D03*
Y103100D03*
X441400Y107300D03*
Y103100D03*
X439500Y241900D03*
Y246100D03*
X444000D03*
Y241900D03*
X439000Y269900D03*
Y274100D03*
X434000Y345400D03*
Y349600D03*
X458500Y113900D03*
Y118100D03*
X453000Y113900D03*
Y118100D03*
X453500Y232400D03*
X457500Y246100D03*
Y241900D03*
X448500Y246100D03*
Y241900D03*
X453500Y236600D03*
X453000Y246100D03*
Y241900D03*
X462000Y246100D03*
Y241900D03*
X453000Y389100D03*
Y384900D03*
X465000Y234100D03*
Y229900D03*
X473500Y350400D03*
Y354600D03*
X478500Y350400D03*
Y354600D03*
X496100Y268600D03*
X496000Y263600D03*
Y259400D03*
X488900Y268600D03*
X496100Y272800D03*
X488900D03*
X488500Y354600D03*
Y350400D03*
X483500D03*
Y354600D03*
X498500D03*
Y350400D03*
X493500Y354600D03*
Y350400D03*
X533100Y223800D03*
Y228000D03*
X527800Y265300D03*
Y261100D03*
X532800Y265300D03*
Y261100D03*
X527000Y276900D03*
Y281100D03*
X531500D03*
Y276900D03*
X541000Y179400D03*
Y183600D03*
X545000Y208900D03*
Y213100D03*
X546500Y232400D03*
Y236600D03*
X564000Y94400D03*
Y98600D03*
X555500Y232400D03*
X560000D03*
X555500Y236600D03*
X560000D03*
X577200Y65800D03*
Y70000D03*
X577500Y75400D03*
Y79600D03*
X570000Y210900D03*
Y215100D03*
X575400Y232400D03*
Y236600D03*
X591902Y195065D03*
Y190865D03*
X596902Y195065D03*
Y190865D03*
X601902D03*
Y195065D03*
X606902D03*
Y190865D03*
X614100Y227800D03*
Y232000D03*
X628900Y197074D03*
Y201274D03*
G54D104*
X558780Y213138D03*
X556220D03*
G54D11*
X6039Y61260D03*
Y81260D03*
Y118346D03*
Y138346D03*
Y175433D03*
Y195433D03*
Y232520D03*
Y252520D03*
X26039Y61260D03*
Y81260D03*
Y118346D03*
Y138346D03*
Y175433D03*
Y195433D03*
Y232520D03*
Y252520D03*
X143567Y106043D03*
X146067Y268043D03*
X268567Y112143D03*
Y255943D03*
G54D123*
G01X51772Y77914D02*
Y73600D01*
G01X59600Y60200D02*
Y60400D01*
X57676Y62324D01*
Y64606D01*
G01X47000Y100000D02*
X50357D01*
G01X51772Y135000D02*
Y130500D01*
G01X51043Y157000D02*
X53900D01*
G01X58000Y148600D02*
Y149500D01*
X60500Y152000D01*
G01X60600Y168945D02*
Y171901D01*
X57676Y174825D01*
Y178779D01*
G01X51772Y192087D02*
Y187987D01*
G01X57500Y209100D02*
Y213000D01*
X58000Y213500D01*
G01X57676Y235866D02*
Y234824D01*
X64000Y228500D01*
Y227100D01*
G01X51772Y249174D02*
Y245074D01*
G01X49657Y268000D02*
Y270500D01*
X48657Y271500D01*
X48500D01*
G01X81999Y266100D02*
X79248D01*
G01X85600Y263700D02*
X85169Y264131D01*
X81999D01*
G01X95593Y333347D02*
X95024Y333916D01*
X89400D01*
G01Y322105D02*
X94395D01*
X95000Y321500D01*
G01X89400Y343758D02*
X94258D01*
X95000Y344500D01*
G01X104500Y305500D02*
X103500D01*
X101473Y307527D01*
Y312000D01*
G01X105410D02*
Y318500D01*
G01X99000Y350000D02*
X99500Y350500D01*
Y357795D01*
X99505Y357800D01*
G01X104019Y347425D02*
Y347519D01*
X105410Y348910D01*
Y357800D01*
G01X114000Y352000D02*
X113000D01*
X111316Y353684D01*
Y357800D01*
G01X107379D02*
Y363121D01*
X106500Y364000D01*
G01X103442Y357800D02*
Y363558D01*
X103000Y364000D01*
G01X110000D02*
X109347Y363347D01*
Y357800D01*
G01X125095Y312000D02*
Y306095D01*
G01X115253Y312000D02*
Y306247D01*
G01X135200Y349664D02*
X130000D01*
G01X124500Y352000D02*
X122501D01*
X121158Y353343D01*
Y357800D01*
G01X129000Y365000D02*
Y363000D01*
X127064Y361064D01*
Y357800D01*
G01X119190D02*
Y363690D01*
X120000Y364500D01*
G01X129043Y379000D02*
X132000D01*
G01X121457D02*
X118500D01*
G01X136000Y-65500D02*
Y-158000D01*
X506000D01*
Y-65500D01*
X136000D01*
G01X135200Y322105D02*
X138595D01*
X140700Y320000D01*
G01X142130Y325630D02*
X140573Y324073D01*
X135200D01*
G01Y333916D02*
X141916D01*
G01X146643Y408600D02*
X148943Y406300D01*
X151530D01*
G01X143500Y414200D02*
Y412101D01*
X144557Y411044D01*
Y408600D01*
G01X147700Y414200D02*
X146643Y413143D01*
Y408600D01*
G01X160860Y403096D02*
X158756Y405200D01*
X158500D01*
G01X151530Y406300D02*
Y403470D01*
X155447Y399553D01*
X158104D01*
G01X151700Y411300D02*
Y410400D01*
X155500Y406600D01*
Y404617D01*
X158104Y402013D01*
G01X153150Y394590D02*
X154176Y395616D01*
X158104D01*
G01X171457Y290000D02*
X169000D01*
G01X173543D02*
X176500D01*
G01X173967Y297562D02*
Y292826D01*
X173543Y292402D01*
Y290000D01*
G01X276986Y185026D02*
X271526D01*
X271000Y184500D01*
G01X276986Y179121D02*
X282200D01*
G01X298500Y184500D02*
Y185000D01*
X296505Y186995D01*
X292734D01*
G01X297772Y188694D02*
X297503Y188963D01*
X292734D01*
G01X316000Y-65500D02*
Y-158000D01*
G01X341500Y233500D02*
Y233384D01*
X342500Y232384D01*
X345152D01*
G01X341953Y240504D02*
Y238000D01*
X340953Y237000D01*
G01X339984Y240504D02*
Y244984D01*
G01X348500Y239500D02*
X347250Y238250D01*
X345192Y238251D01*
X345152Y238290D01*
G01X360700Y389200D02*
X360900D01*
X362300Y387800D01*
G01X354843Y389200D02*
Y387056D01*
X356400Y385499D01*
Y383300D01*
G01X352757Y389200D02*
Y386557D01*
X352200Y386000D01*
Y383300D01*
G01X347000Y391200D02*
X350757D01*
X352757Y389200D01*
G01X344300Y385800D02*
Y393283D01*
X341796Y395787D01*
G01X359800Y397700D02*
X358800Y398700D01*
X356400D01*
G01X354843Y394700D02*
X358500D01*
X359800Y396000D01*
Y397700D01*
G01X347600Y398800D02*
Y398300D01*
X351200Y394700D01*
X352757D01*
G01X341796Y400216D02*
X346284D01*
X347600Y398900D01*
Y398800D01*
G01X341796Y398247D02*
X344153D01*
X346300Y396100D01*
Y391900D01*
X347000Y391200D01*
G01X341796Y402184D02*
X347816D01*
X349500Y400500D01*
X350400D01*
X352200Y398700D01*
G01X423910Y397231D02*
X431269D01*
X432000Y396500D01*
G01X441975Y286616D02*
X449516D01*
X452400Y289500D01*
G01X435600Y287600D02*
X436584Y286616D01*
G01D02*
X441975D01*
G01X529043Y272500D02*
X532500D01*
G01X543957Y63500D02*
Y60543D01*
G01X559500Y228000D02*
Y226500D01*
X558484Y225484D01*
Y221996D01*
G01X564000Y232957D02*
Y231000D01*
X561500Y228500D01*
X560000D01*
X559500Y228000D01*
G01X566700Y227500D02*
X563500D01*
X560453Y224453D01*
Y221996D01*
G01X569500Y233457D02*
X566700Y230657D01*
Y227500D01*
G01X556516Y221996D02*
Y228516D01*
X560000Y232000D01*
Y232400D01*
G01X553800Y240200D02*
X555500Y238500D01*
Y236600D01*
G01X560000D02*
X562443D01*
X564000Y235043D01*
G01X573100Y79600D02*
X577500D01*
G01X577100Y224500D02*
Y227900D01*
G01X569500Y233457D02*
X570557Y232400D01*
X575400D01*
G01X569500Y235543D02*
X572300D01*
X573357Y236600D01*
X575400D01*
G01X601953Y214382D02*
Y218853D01*
G01D02*
Y221553D01*
X602900Y222500D01*
G54D114*
X605315Y367519D03*
G54D21*
X24807Y335985D03*
Y347245D03*
X43705Y331655D03*
Y351576D03*
G54D30*
X78260Y224650D03*
Y242750D03*
X85940Y224650D03*
X83380D03*
X80820D03*
X83380Y242750D03*
X80820D03*
X85940D03*
X209660Y308450D03*
X212220D03*
X214780D03*
X217340D03*
X209660Y326550D03*
X212220D03*
X214780D03*
X217340D03*
G54D12*
X6874Y91633D03*
Y102067D03*
Y159154D03*
Y148720D03*
Y216241D03*
Y205807D03*
Y262893D03*
Y273327D03*
Y319980D03*
Y330414D03*
G54D105*
X556516Y221996D03*
X560453D03*
X554547D03*
X558484D03*
G54D124*
G01X62500Y112600D02*
X61992D01*
X57676Y116916D01*
Y121692D01*
G01X57500Y218500D02*
X54000D01*
X52100Y216600D01*
X51643D01*
G01X51452Y223300D02*
Y219900D01*
G01X69500Y100000D02*
X71500Y98000D01*
X72462D01*
X73662Y96800D01*
Y94750D01*
G01X140123Y391604D02*
Y391377D01*
X141400Y390100D01*
X145057D01*
G01X143500Y394600D02*
X141100D01*
X140100Y395600D01*
G01X145057Y403100D02*
X143500Y401543D01*
Y399100D01*
G01X147700D02*
X149200Y397600D01*
X150140D01*
X153150Y394590D01*
G01X144557Y408600D02*
X144357Y408400D01*
X138500D01*
G01X272330Y54871D02*
Y56331D01*
X273940Y57941D01*
X275400D01*
G01X284800Y63059D02*
X289141D01*
X290100Y62100D01*
X295500D01*
G01X293700Y320600D02*
X302307D01*
X304250Y322543D01*
G01X293700Y320600D02*
Y317300D01*
G01X321899Y343000D02*
X324442Y340457D01*
X328150D01*
G01X339040Y394704D02*
Y393060D01*
X340500Y391600D01*
G01X343700Y409900D02*
X340240D01*
X339040Y408700D01*
Y407696D01*
G01X358200Y276100D02*
X354850D01*
G01X358200Y289800D02*
X354800D01*
G01X354843Y389200D02*
X360700D01*
G01X360000Y402400D02*
X359200Y403200D01*
X356400D01*
G01X354743Y412100D02*
X358800D01*
X360000Y410900D01*
Y410191D01*
X360311Y409880D01*
G01X367000Y232000D02*
X364230D01*
X363673Y232557D01*
G01Y241243D02*
X367000D01*
G01X396400Y97000D02*
X391100D01*
G01X378000Y273500D02*
X379000Y272500D01*
X381600D01*
G01X391200Y288533D02*
Y282900D01*
X389400Y281100D01*
G01D02*
X385800Y277500D01*
G01X393300Y309200D02*
Y312500D01*
G01X383000Y341500D02*
X380000Y338500D01*
X376900D01*
G01X396400Y97000D02*
Y100500D01*
G01X410100Y97000D02*
X409200Y97900D01*
Y100500D01*
G01X396243Y277400D02*
X398800D01*
X399800Y278400D01*
G01X395138Y300467D02*
Y302639D01*
X396981Y304482D01*
G01X397500Y312900D02*
X398200Y312200D01*
Y310043D01*
G01X396981Y304482D02*
X398200Y305701D01*
Y307957D01*
G01X412350Y397150D02*
X410300Y399200D01*
X404890D01*
G01X416450Y397150D02*
X414400Y395100D01*
Y389690D01*
G01X412350Y401250D02*
X414400Y403300D01*
Y408710D01*
G01X416450Y401250D02*
X418500Y399200D01*
X423910D01*
G01X436406Y192217D02*
X438374Y194185D01*
G01X446500Y289500D02*
X445499D01*
X444583Y288584D01*
X441975D01*
G01X496100Y272800D02*
X493100D01*
X492500Y272200D01*
G01X495257Y277700D02*
X491800D01*
G01X500000Y278799D02*
X498442D01*
X497343Y277700D01*
G01X504833Y274638D02*
X500405D01*
X497343Y277700D01*
G01X527800Y265300D02*
X532800D01*
G01X522400Y270700D02*
X527800Y265300D01*
G01X524300Y261700D02*
X524900Y261100D01*
G01D02*
X527800D01*
G01X522400Y270700D02*
X516767D01*
G01X548300Y222600D02*
Y221200D01*
X550260Y219240D01*
X551004D01*
G01X551000Y235043D02*
Y236499D01*
X552300Y237799D01*
Y238700D01*
X553800Y240200D01*
G01X566950Y220000D02*
X566400D01*
X565640Y219240D01*
X563996D01*
G01X562913Y221996D02*
X564217Y223300D01*
X569943D01*
G01X578043Y60900D02*
X580643D01*
G01X577200Y65800D02*
X580500D01*
G01X568467Y63962D02*
X572895D01*
X575957Y60900D01*
G01X572500Y60301D02*
X575358D01*
X575957Y60900D01*
G01X569943Y223300D02*
X571700D01*
X572900Y224500D01*
G01X569600Y240000D02*
X569500Y239900D01*
Y235543D01*
G54D115*
X608450Y100660D03*
Y108340D03*
Y105780D03*
Y103220D03*
X626550Y108340D03*
Y100660D03*
Y103220D03*
Y105780D03*
G54D22*
X57676Y64606D03*
X51772Y77914D03*
X53740D03*
X55708Y64606D03*
X51772D03*
X53740D03*
X57676Y77914D03*
X55708D03*
X57676Y121692D03*
X55708D03*
X51772D03*
X53740D03*
X51772Y135000D03*
X53740D03*
X57676D03*
X55708D03*
X57676Y178779D03*
X55708D03*
X51772D03*
X53740D03*
X51772Y192087D03*
X53740D03*
X57676D03*
X55708D03*
X57676Y235866D03*
X51772Y249174D03*
X53740D03*
X55708Y235866D03*
X51772D03*
X53740D03*
X57676Y249174D03*
X55708D03*
G54D40*
X97536Y312000D03*
Y357800D03*
X113284Y312000D03*
X111316D03*
X109347D03*
X107379D03*
X105410D03*
X103442D03*
X101473D03*
X99505D03*
Y357800D03*
X101473D03*
X103442D03*
X105410D03*
X107379D03*
X109347D03*
X111316D03*
X113284D03*
X127064Y312000D03*
X125095D03*
X123127D03*
X121158D03*
X119190D03*
X117221D03*
X115253D03*
Y357800D03*
X117221D03*
X119190D03*
X121158D03*
X123127D03*
X125095D03*
X127064D03*
G54D13*
X8252Y98523D03*
Y95177D03*
Y155610D03*
Y152264D03*
Y212697D03*
Y209351D03*
Y266437D03*
Y269783D03*
Y326870D03*
Y323524D03*
G54D106*
X562913Y221996D03*
X552087D03*
G54D31*
X75897Y266100D03*
Y264131D03*
Y268069D03*
X81999D03*
Y266100D03*
Y264131D03*
G54D125*
G01X12500Y96000D02*
X11677Y95177D01*
X8252D01*
G01Y152264D02*
X11264D01*
G01X8252Y209351D02*
X12351D01*
X12500Y209500D01*
G01X8252Y266437D02*
X11963D01*
G01X8252Y323524D02*
X11976D01*
G01X17500Y91000D02*
X20550Y94050D01*
Y95650D01*
G01X17000Y204500D02*
X20550Y208050D01*
Y209650D01*
G01X44300Y68900D02*
X47600D01*
G01X45200Y236800D02*
X42000D01*
G01X59000Y96500D02*
X58000Y95500D01*
Y92600D01*
G01X62500Y108400D02*
Y106000D01*
X61400Y104900D01*
G01X50500Y108390D02*
Y104800D01*
G01X45500Y122000D02*
Y126000D01*
G01X62500Y112600D02*
Y117000D01*
G01X45500Y164400D02*
Y161000D01*
G01X60600Y164745D02*
Y161200D01*
G01X51400Y165000D02*
Y161600D01*
G01X60600Y168945D02*
X64445D01*
G01X54590Y266870D02*
X57800Y263660D01*
Y261100D01*
G01X61900Y279000D02*
Y279900D01*
X65100Y283100D01*
X67000D01*
G01X61489Y332329D02*
X62755Y331063D01*
Y330994D01*
X63100Y330649D01*
Y329000D01*
G01X59500Y359600D02*
X63500D01*
G01X74593Y209100D02*
Y202207D01*
G01X71400Y225200D02*
Y221700D01*
G01X64000Y222900D02*
X67500D01*
G01X64000Y227100D02*
X67400D01*
G01X71400Y229400D02*
Y232900D01*
G01Y229400D02*
X75800D01*
X78260Y226940D01*
Y224650D01*
G01X71500Y244400D02*
Y247800D01*
G01Y240200D02*
Y239900D01*
X68000Y236400D01*
Y235500D01*
G01X71500Y240200D02*
X73600Y238100D01*
X76000D01*
X78260Y240360D01*
Y242750D01*
G01X83500Y252400D02*
X83000D01*
X82900Y252500D01*
X81296D01*
X80148Y253648D01*
G01X76948Y252500D02*
X73600D01*
G01X64248Y261400D02*
Y258000D01*
G01X68600Y274000D02*
X68448Y273848D01*
Y270900D01*
G01X72000Y339350D02*
Y335000D01*
G01Y350650D02*
Y346300D01*
G01X88900Y67000D02*
X89000D01*
X91100Y69100D01*
X95750D01*
G01X81339Y70850D02*
Y78539D01*
X82100Y79300D01*
G01X85750Y202750D02*
X86207Y203207D01*
Y209100D01*
G01X86800Y230000D02*
Y227800D01*
X85940Y226940D01*
Y224650D01*
G01X90700Y258048D02*
X87723D01*
X87671Y258100D01*
X87400D01*
X87200Y258300D01*
G01X87100Y271300D02*
X87000Y271400D01*
G01D02*
Y277000D01*
X85100Y278900D01*
X80648D01*
G01X111330Y59810D02*
X109850D01*
X107050Y62610D01*
Y65360D01*
G01X117370Y61360D02*
X112880D01*
X111330Y59810D01*
G01X102500Y298100D02*
Y302000D01*
G01X115500Y389000D02*
X116500Y388000D01*
Y382000D01*
X118500Y380000D01*
Y379000D01*
G01X117000Y397000D02*
X115500Y395500D01*
Y389000D01*
G01X121570Y61360D02*
Y59764D01*
X119500Y57694D01*
G01X121570Y75360D02*
Y70860D01*
G01X125000Y76500D02*
X123860Y75360D01*
X121570D01*
G01X117500Y293900D02*
Y290000D01*
G01X129000Y321500D02*
X130364Y320136D01*
X135200D01*
G01X129000Y365000D02*
Y370500D01*
G01X132000Y375500D02*
Y373500D01*
X129000Y370500D01*
G01X120000Y371500D02*
Y372000D01*
X119500Y372500D01*
Y376000D01*
X118500Y377000D01*
Y379000D01*
G01X135500Y383000D02*
Y377500D01*
X133500Y375500D01*
X132000D01*
G01X129831Y385154D02*
X133346D01*
X135500Y383000D01*
G01Y396000D02*
X134439Y397061D01*
X127000D01*
G01X121169Y391846D02*
Y396892D01*
G01D02*
X126831D01*
X127000Y397061D01*
G01X121169Y396892D02*
X117108D01*
X117000Y397000D01*
G01X140100Y306900D02*
Y315400D01*
X143900Y319200D01*
X145500D01*
G01X135500Y396000D02*
Y390500D01*
G01D02*
Y383000D01*
G01X143500Y399100D02*
X141900D01*
X140000Y401000D01*
G01X138500Y408400D02*
X135200D01*
G01X138500Y412600D02*
X135100D01*
G01X154800Y62120D02*
Y59930D01*
X153270Y58400D01*
G01X154800Y62120D02*
X158150D01*
X161270Y59000D01*
X166220D01*
G01X150860Y67400D02*
X151940Y66320D01*
X154800D01*
G01X151000Y320600D02*
Y324200D01*
G01X155600Y416200D02*
X152300D01*
X152200Y416300D01*
G01X151700Y411300D02*
X152400Y412000D01*
X155600D01*
G01X183661Y13781D02*
Y28900D01*
G01D02*
X180900D01*
X179724Y27724D01*
Y13781D01*
G01X183661Y28900D02*
X187598D01*
G01X184387Y397600D02*
X177400D01*
X177000Y398000D01*
G01X191535Y13781D02*
Y28900D01*
G01X187598D02*
Y13781D01*
G01X203346D02*
Y27654D01*
X201950Y29050D01*
G01X188320Y74000D02*
X192160Y77840D01*
G01X195900Y328900D02*
Y332500D01*
G01X213500Y54000D02*
Y52000D01*
X215000Y50500D01*
Y35810D01*
X216800Y34010D01*
Y29000D01*
X215157Y27357D01*
Y13781D01*
G01X207283D02*
Y27283D01*
X210500Y30500D01*
G01X215000Y59400D02*
Y56500D01*
X213500Y55000D01*
Y54000D01*
G01X215000Y59400D02*
X210500D01*
G01X215000Y63600D02*
Y69000D01*
G01X210500Y63600D02*
X215000D01*
G01X204770Y63200D02*
Y67780D01*
G01D02*
X205040Y68050D01*
X207750D01*
X213800Y74100D01*
X226900D01*
X227800Y75000D01*
X228000D01*
X228500Y75500D01*
G01X212800Y289500D02*
Y293100D01*
G01X208300D02*
X212800D01*
G01D02*
X217300D01*
G01X217340Y308450D02*
Y306660D01*
X221800Y302200D01*
Y297300D01*
G01X209660Y326550D02*
Y331500D01*
G01X232700Y29100D02*
X234842Y26958D01*
Y13781D01*
G01X221800Y289500D02*
Y293100D01*
G01Y297300D02*
X223200D01*
X224700Y298800D01*
Y301800D01*
X224500Y302000D01*
G01X254527Y13781D02*
Y28900D01*
G01X244619D02*
X246653Y26866D01*
Y13781D01*
G01X304200Y365200D02*
X254950D01*
X238000Y348250D01*
Y345000D01*
G01X264304Y28900D02*
X266338Y26866D01*
Y13781D01*
G01X272309Y28900D02*
X270275Y26866D01*
Y13781D01*
G01X259500Y60500D02*
Y54700D01*
G01Y70100D02*
Y65500D01*
G01X280052Y28900D02*
X282086Y26866D01*
Y13781D01*
G01X288057Y28900D02*
X286023Y26866D01*
Y13781D01*
G01X289500Y320600D02*
Y318000D01*
X288500Y317000D01*
G01X295800Y28900D02*
X297834Y26866D01*
Y13781D01*
G01X303500Y69400D02*
X301900D01*
X299720Y67220D01*
Y66780D01*
G01X295520D02*
Y69320D01*
X296400Y70200D01*
G01X295520Y66780D02*
Y62120D01*
X295500Y62100D01*
G01X300995Y187611D02*
X299912Y188694D01*
X297772D01*
G01X307500Y368500D02*
X304200Y365200D01*
G01X309645Y13781D02*
Y26963D01*
X307708Y28900D01*
G01X312400Y164500D02*
X309000D01*
G01X312000Y217000D02*
X312600Y216400D01*
X315900D01*
G01X325400Y216500D02*
Y219100D01*
X324000Y220500D01*
Y220750D01*
G01D02*
X323750D01*
X323600Y220900D01*
X320100D01*
G01X315900Y234400D02*
X312000D01*
G01X315900Y243400D02*
X311900D01*
G01X315900Y238900D02*
Y243400D01*
G01X323744Y276500D02*
X314500D01*
G01X323744Y286500D02*
X328500D01*
X330500Y288500D01*
Y291500D01*
G01X315000Y368500D02*
X307500D01*
G01X521500Y60000D02*
X519500Y58000D01*
X362000D01*
X355500Y64500D01*
X346500D01*
X341750Y59750D01*
X337310D01*
X336000Y61060D01*
G01X529500Y60500D02*
X525500Y64500D01*
X519000D01*
X516000Y61500D01*
X363000D01*
X356500Y68000D01*
X345000D01*
X340500Y63500D01*
G01X328500Y258900D02*
Y255300D01*
G01X338484D02*
X343500D01*
G01X333500Y258900D02*
Y255300D01*
G01X341000Y304000D02*
X341400Y304400D01*
Y323500D01*
G01X348100D02*
X341400D01*
G01X350500Y229500D02*
X364999D01*
X367000Y231501D01*
Y232000D01*
G01X355000Y242500D02*
X360000D01*
X360500Y243000D01*
G01X349100Y247698D02*
Y250900D01*
G01X345698D02*
X349100D01*
G01X343500Y258900D02*
Y255300D01*
G01X349100Y256300D02*
Y259400D01*
X348500Y260000D01*
G01X354600Y255500D02*
X354100Y256000D01*
X349400D01*
X349100Y256300D01*
G01X358000Y261500D02*
X357500D01*
X356000Y260000D01*
X352500D01*
G01X357680Y271780D02*
X364720D01*
X365500Y271000D01*
X368900D01*
G01X358200Y280300D02*
Y285600D01*
G01D02*
X354800D01*
G01X362300Y383600D02*
Y375050D01*
X352450Y365200D01*
X348000D01*
G01X344300Y381600D02*
X347700D01*
G01D02*
X348000Y381300D01*
Y379400D01*
X349400Y378000D01*
G01X352200Y383300D02*
Y380700D01*
X352550Y380350D01*
Y379050D01*
X353600Y378000D01*
G01X360311Y409880D02*
Y409701D01*
X358310Y407700D01*
X356400D01*
G01X379500Y72500D02*
X376500D01*
X373500Y75500D01*
Y78000D01*
G01D02*
X370061D01*
X366500Y81561D01*
Y85500D01*
X373500Y92500D01*
Y94000D01*
G01D02*
Y98675D01*
X375055Y100230D01*
X376838D01*
G01X376900Y97000D02*
Y100168D01*
X376838Y100230D01*
G01X369172Y102828D02*
X370194Y103850D01*
X370950D01*
X373100Y106000D01*
X373200D01*
G01D02*
X373300D01*
X369800Y109500D01*
X369310D01*
G01X363600Y176600D02*
X363327D01*
X361276Y174549D01*
X360400D01*
G01X367000Y241243D02*
Y232000D01*
G01X372500D02*
X370500Y234000D01*
Y238400D01*
G01X367000Y241243D02*
Y242243D01*
X365743Y243500D01*
X361000D01*
X360500Y243000D01*
G01X373240Y251350D02*
Y247260D01*
X373260Y247240D01*
G01D02*
X373191Y247171D01*
X371069D01*
X369500Y248740D01*
Y251350D01*
G01X373260Y247240D02*
X373500Y247000D01*
G01X376000Y238400D02*
X378600D01*
X379500Y237500D01*
G01X369500Y262650D02*
Y267500D01*
G01X380100Y255200D02*
X375800D01*
G01X379500Y417500D02*
Y389500D01*
X373600Y383600D01*
Y368100D01*
X366000Y360500D01*
Y350850D01*
G01X413622Y75000D02*
X413500Y74878D01*
Y72600D01*
X412000Y71100D01*
X380900D01*
X379500Y72500D01*
G01X396400Y100500D02*
X390000D01*
G01X384000Y102980D02*
X383580Y103400D01*
X382500D01*
X379900Y106000D01*
X379800D01*
G01D02*
X380300Y106500D01*
Y106600D01*
X382100Y108400D01*
X382900D01*
X384000Y109500D01*
G01X390000Y100500D02*
X389730Y100230D01*
X376838D01*
G01X389161Y137098D02*
X387193Y135130D01*
G01X393098Y141035D02*
X391130Y139067D01*
G01X389161Y141035D02*
X387193Y139067D01*
G01X389161Y148910D02*
X387193Y146942D01*
G01X393098Y148910D02*
X391130Y146942D01*
G01X389161Y156784D02*
X387193Y154816D01*
G01X389161Y164658D02*
X387193Y162690D01*
G01X393098Y164658D02*
X391130Y162690D01*
G01X393098Y156784D02*
X391130Y154816D01*
G01X389161Y172532D02*
X387193Y170564D01*
G01X393098Y176469D02*
X391130Y178437D01*
G01X389161Y176469D02*
X387193Y178437D01*
G01X393098Y172532D02*
X391130Y170564D01*
G01X393098Y184343D02*
X391130Y186311D01*
G01X389161Y196154D02*
X385500D01*
G01X393098Y204028D02*
X391130Y205996D01*
G01X389161Y215839D02*
X387193Y217807D01*
G01X381600Y268000D02*
Y272500D01*
G01X385800D02*
Y268000D01*
G01X380100Y255200D02*
X386000D01*
G01D02*
X391900D01*
G01D02*
X397800D01*
G01X386000D02*
Y259250D01*
G01X385800Y272500D02*
Y277500D01*
G01X378000Y277400D02*
X378100Y277500D01*
G01X381600D02*
Y280400D01*
G01D02*
X382200Y281000D01*
G01X378100Y277500D02*
X381600D01*
G01X413622Y75000D02*
X413405Y75217D01*
X408000D01*
G01X409200Y100500D02*
X412000D01*
X413500Y99000D01*
Y88500D01*
G01X399500Y120000D02*
X399000D01*
X396400Y117400D01*
Y100500D01*
G01X409200D02*
X410100Y101400D01*
Y114600D01*
X410625Y115125D01*
Y117787D01*
X408501Y119911D01*
X407089D01*
X407000Y120000D01*
G01X397035Y141035D02*
X395067Y139067D01*
G01X400973Y141035D02*
X399005Y139067D01*
G01X400973Y144973D02*
X399005Y143005D01*
G01X404910Y144973D02*
X402942Y143005D01*
G01X404910Y148910D02*
X402942Y146942D01*
G01X408847Y148910D02*
X406879Y146942D01*
G01X412784Y148910D02*
X410816Y146942D01*
G01X397035Y144973D02*
X395067Y143005D01*
G01X397035Y133161D02*
X395067Y131193D01*
G01X408847Y137098D02*
X406879Y135130D01*
G01X397035Y152847D02*
X395067Y150879D01*
G01X404910Y156784D02*
X402942Y154816D01*
G01X400973Y160721D02*
X399005Y158753D01*
G01X412784Y160721D02*
X410816Y158753D01*
G01X404910Y164658D02*
X402942Y162690D01*
G01X412784Y164658D02*
X410816Y162690D01*
G01X412784Y152847D02*
X410816Y150879D01*
G01X412784Y156784D02*
X410816Y154816D01*
G01X397035Y160721D02*
X395067Y158753D01*
G01X400973Y152847D02*
X399005Y150879D01*
G01X404910Y160721D02*
X402942Y158753D01*
G01X408847Y164658D02*
X406879Y162690D01*
G01X408847Y156784D02*
X406879Y154816D01*
G01X397035Y168595D02*
X395067Y166627D01*
G01X412784Y168595D02*
X410816Y166627D01*
G01X404910Y172532D02*
X402942Y170564D01*
G01X408847Y172532D02*
X406879Y170564D01*
G01X397035Y176469D02*
X395067Y178437D01*
G01X400973Y176469D02*
X399005Y178437D01*
G01X412784Y176469D02*
X410816Y178437D01*
G01X400973Y180406D02*
X399005Y182374D01*
G01X400973Y168595D02*
X399005Y166627D01*
G01X404910Y176469D02*
X402942Y178437D01*
G01X408847Y176469D02*
X406879Y178437D01*
G01X408847Y196154D02*
X406879Y198122D01*
G01X412784Y184343D02*
X410816Y186311D01*
G01X397035Y192217D02*
X395067Y194185D01*
G01X404910Y188280D02*
X402942Y190248D01*
G01X404910Y207965D02*
X402942Y209933D01*
G01X412784Y204028D02*
X410816Y205996D01*
G01X408847Y215839D02*
X406879Y217807D01*
G01X397035Y211902D02*
X395067Y213870D01*
G01X400973Y200091D02*
X399005Y202059D01*
G01X396800Y268000D02*
X397500D01*
X400000Y265500D01*
G01X397800Y255200D02*
X403700D01*
G01D02*
X409300D01*
G01D02*
X415000D01*
G01X407500Y305000D02*
X410500D01*
X412143Y306643D01*
X416950D01*
G01X398000Y340560D02*
Y336500D01*
G01Y348040D02*
Y352000D01*
G01X403550Y358543D02*
X410000D01*
G01X413500Y88500D02*
X413622Y88378D01*
Y75000D01*
G01X434500Y77000D02*
X434000Y77500D01*
X422000D01*
G01D02*
X419000D01*
X416500Y80000D01*
Y94000D01*
X423000Y100500D01*
G01X431400Y90634D02*
X428466Y87700D01*
X425000D01*
G01X420500Y92100D02*
X422000D01*
X425000Y89100D01*
Y87700D01*
G01X431000Y116500D02*
X426063Y111563D01*
Y103563D01*
X423000Y100500D01*
G01X416721Y133161D02*
X414753Y131193D01*
G01X424595Y148910D02*
X422627Y146942D01*
G01X428532Y137098D02*
X426564Y135130D01*
G01X420658Y141035D02*
X418690Y139067D01*
G01X416721Y164658D02*
X414753Y162690D01*
G01X416721Y156784D02*
X414753Y154816D01*
G01X420658Y160721D02*
X418690Y158753D01*
G01X424595Y164658D02*
X422627Y162690D01*
G01X424595Y156784D02*
X422627Y154816D01*
G01X428532Y164658D02*
X426564Y162690D01*
G01X428532Y160721D02*
X426564Y158753D01*
G01X420658Y156784D02*
X418690Y154816D01*
G01X420658Y164658D02*
X418690Y162690D01*
G01X416721Y160721D02*
X414753Y158753D01*
G01X424595Y160721D02*
X422627Y158753D01*
G01X428532Y156784D02*
X426564Y154816D01*
G01X416721Y152847D02*
X414753Y150879D01*
G01X420658Y168595D02*
X418690Y166627D01*
G01X416721Y172532D02*
X414753Y170564D01*
G01X424595Y172532D02*
X422627Y170564D01*
G01X420658Y176469D02*
X418690Y178437D01*
G01X428532Y168595D02*
X426564Y166627D01*
G01X420658Y172532D02*
X418690Y170564D01*
G01X416721Y168595D02*
X414753Y166627D01*
G01X428532Y172532D02*
X426564Y170564D01*
G01X416721Y176469D02*
X414753Y178437D01*
G01X424595Y168595D02*
X422627Y166627D01*
G01X424595Y176469D02*
X422627Y178437D01*
G01X420658Y180406D02*
X418690Y182374D01*
G01X424595Y188280D02*
X422627Y190248D01*
G01X428532Y196154D02*
X426564Y198122D01*
G01X416721Y192217D02*
X414753Y194185D01*
G01X416721Y211902D02*
X414753Y213870D01*
G01X420658Y200091D02*
X418690Y202059D01*
G01X428532Y215839D02*
X426564Y217807D01*
G01X424595Y207965D02*
X422627Y209933D01*
G01X415000Y255200D02*
X420900D01*
G01D02*
Y259000D01*
G01X433000Y276500D02*
X431500D01*
X429000Y274000D01*
G01X417500Y340760D02*
Y337000D01*
G01Y348240D02*
Y352000D01*
G01X427450Y376457D02*
X431957D01*
X434500Y379000D01*
X438400D01*
G01X434500Y77000D02*
X440300D01*
X441400Y78100D01*
G01Y82366D02*
Y78100D01*
G01X448430Y89540D02*
Y80120D01*
X446310Y78000D01*
X441500D01*
X441400Y78100D01*
G01X432200Y97300D02*
Y99200D01*
X433500Y100500D01*
G01X446000Y97300D02*
Y98700D01*
X444200Y100500D01*
G01X450000Y108200D02*
X447350D01*
X445850Y109700D01*
Y112300D01*
G01X429400Y107500D02*
X432450Y110550D01*
Y112300D01*
G01X450000Y108200D02*
Y114000D01*
X448000Y116000D01*
X444649D01*
X444050Y116599D01*
G01X440343Y141035D02*
X442311Y139067D01*
G01X432469Y144973D02*
X434437Y143005D01*
G01X436406Y133161D02*
X438374Y131193D01*
G01X444280Y160721D02*
X446248Y158753D01*
G01X440343Y164658D02*
X442311Y162690D01*
G01X432469Y164658D02*
X434437Y162690D01*
G01X432469Y156784D02*
X434437Y154816D01*
G01X436406Y164658D02*
X438374Y162690D01*
G01X436406Y152847D02*
X438374Y150879D01*
G01X436406Y160721D02*
X438374Y158753D01*
G01X440343Y156784D02*
X442311Y154816D01*
G01X432469Y160721D02*
X434437Y158753D01*
G01X440343Y160721D02*
X442311Y158753D01*
G01X436406Y156784D02*
X438374Y154816D01*
G01X444280Y156784D02*
X446248Y154816D01*
G01X444280Y164658D02*
X446248Y162690D01*
G01X444280Y148910D02*
X446248Y146942D01*
G01X436406Y168595D02*
X438374Y166627D01*
G01X444280Y168595D02*
X446248Y166627D01*
G01X432469Y172532D02*
X434437Y170564D01*
G01X440343Y172532D02*
X442311Y170564D01*
G01X444280Y176469D02*
X446248Y178437D01*
G01X440343Y180406D02*
X442311Y182374D01*
G01X432469Y168595D02*
X434437Y166627D01*
G01X436406Y172532D02*
X438374Y170564D01*
G01X440343Y168595D02*
X442311Y166627D01*
G01X432469Y176469D02*
X434437Y178437D01*
G01X444280Y172532D02*
X446248Y170564D01*
G01X440343Y176469D02*
X442311Y178437D01*
G01X444280Y188280D02*
X446248Y190248D01*
G01X432469Y184343D02*
X434437Y186311D01*
G01X432469Y204028D02*
X434437Y205996D01*
G01X444280Y207965D02*
X446248Y209933D01*
G01X436406Y211902D02*
X438374Y213870D01*
G01X440343Y200091D02*
X442311Y202059D01*
G01X444000Y246100D02*
Y250000D01*
G01X439500Y246100D02*
Y250000D01*
G01X438150Y283800D02*
X439521Y282429D01*
X441975D01*
G01X450900Y327000D02*
X448000D01*
X445557Y324557D01*
X440850D01*
G01X449000Y370000D02*
X442600D01*
G01Y374500D02*
Y379000D01*
G01Y374500D02*
X446000D01*
G01X439600Y386500D02*
X443000D01*
G01X438400Y379000D02*
Y382400D01*
G01X439600Y396500D02*
Y401500D01*
G01Y391500D02*
Y396500D01*
G01Y401500D02*
X443000D01*
G01X432000Y396500D02*
X435400D01*
G01X448430Y89540D02*
X450000Y91110D01*
Y97500D01*
X451500Y99000D01*
Y106700D01*
X450000Y108200D01*
G01X453000Y113900D02*
X458500D01*
G01X462500Y117000D02*
Y116000D01*
X460400Y113900D01*
X458500D01*
G01X452154Y144973D02*
X454122Y143005D01*
G01X456091Y133161D02*
X457844Y131408D01*
G01X448217Y137098D02*
X450185Y135130D01*
G01X460028Y141035D02*
X461996Y139067D01*
G01X463965Y148910D02*
X465933Y146942D01*
G01X448217Y156784D02*
X450185Y154816D01*
G01X460028Y160721D02*
X461996Y158753D01*
G01X448217Y164658D02*
X450185Y162690D01*
G01X448217Y160721D02*
X450185Y158753D01*
G01X456091Y152847D02*
X458059Y150879D01*
G01X448217Y172532D02*
X450185Y170564D01*
G01X456091Y172532D02*
X454123Y170564D01*
G01X448217Y168595D02*
X450185Y166627D01*
G01X460028Y180406D02*
X461996Y182374D01*
G01X448217Y176469D02*
X450185Y178437D01*
G01X463965Y168595D02*
X465933Y166627D01*
G01X452154Y184343D02*
X454122Y186311D01*
G01X463965Y188280D02*
X465933Y190248D01*
G01X448217Y196154D02*
X450185Y198122D01*
G01X456091Y192217D02*
X458059Y194185D01*
G01X460028Y200091D02*
X461996Y202059D01*
G01X456091Y211902D02*
X458059Y213870D01*
G01X463965Y207965D02*
X465933Y209933D01*
G01X452154Y204028D02*
X454122Y205996D01*
G01X448217Y215839D02*
X450185Y217807D01*
G01X457500Y246100D02*
Y250000D01*
G01X456600Y284500D02*
X460000D01*
G01X456600Y294500D02*
Y289500D01*
G01D02*
X460000D01*
G01X455400Y322000D02*
X459500D01*
G01X455100Y327000D02*
X455400Y326700D01*
Y322000D01*
G01X455100Y327000D02*
X458000D01*
X459000Y326000D01*
G01X450900Y327000D02*
Y330900D01*
G01X447200Y353150D02*
Y347500D01*
G01X450500Y368500D02*
X449000Y370000D01*
G01X481000Y70700D02*
Y72010D01*
X483033Y74043D01*
X488550D01*
G01X465500Y78500D02*
Y82600D01*
X469400Y86500D01*
G01Y78500D02*
X465500D01*
G01X467902Y137098D02*
X469870Y135130D01*
G01X471839Y144973D02*
X473807Y143005D01*
G01X467902Y156784D02*
X469870Y154816D01*
G01X467902Y176469D02*
X469870Y178437D01*
G01X473807Y166627D02*
X471839Y164659D01*
Y164658D01*
G01X467902Y196154D02*
X469870Y198122D01*
G01X471839Y184343D02*
X473807Y186311D01*
G01X471839Y204028D02*
X473807Y205996D01*
G01X467902Y215839D02*
X469870Y217807D01*
G01X473500Y350400D02*
X471000Y347900D01*
Y347000D01*
G01X478656Y367205D02*
X475305D01*
X471400Y363300D01*
G01X493300Y126400D02*
Y121500D01*
G01X489400Y126300D02*
X490580D01*
X490680Y126400D01*
X493300D01*
G01X497000Y175000D02*
Y171000D01*
X498750Y169250D01*
Y166360D01*
X496000Y163610D01*
Y163000D01*
G01X492600Y172000D02*
Y167500D01*
G01D02*
X496000D01*
G01X492600Y176500D02*
X495500D01*
X497000Y175000D01*
G01X490500Y216750D02*
X492600Y214650D01*
Y211500D01*
G01X493500Y350400D02*
Y347500D01*
X495000Y346000D01*
G01X524900Y92000D02*
X515900D01*
X515857Y91957D01*
X512450D01*
G01X499900Y126400D02*
X502190Y128690D01*
X503900D01*
G01X503860Y124150D02*
X502150D01*
X499900Y126400D01*
G01X500100Y143000D02*
X503950D01*
G01X500100Y138500D02*
Y133500D01*
G01D02*
X503950D01*
G01X526500Y67500D02*
X528000Y69000D01*
Y71280D01*
X529100Y72380D01*
Y76000D01*
G01X533000Y87000D02*
X529100D01*
G01D02*
Y92000D01*
G01Y82000D02*
X533000D01*
G01X524900Y99000D02*
Y92000D01*
G01X532800Y261100D02*
X530750Y259050D01*
Y258975D01*
X530350Y258575D01*
Y257480D01*
G01X526500Y254000D02*
X534100D01*
X534500Y253600D01*
G01X527000Y281100D02*
X523600D01*
G01X537500Y304000D02*
X522500D01*
X519000Y307500D01*
G01X528300Y415049D02*
X525176Y411925D01*
G01X544500Y79500D02*
X540400Y75400D01*
Y69000D01*
G01X551700Y256300D02*
X550544Y257456D01*
Y262100D01*
G01Y302100D02*
X542753D01*
X541346Y303507D01*
G01X546443Y396700D02*
X543000D01*
G01X555315Y407875D02*
X543504D01*
G01D02*
X538500D01*
G01X560000Y236600D02*
Y240000D01*
G01X565400D02*
Y244700D01*
G01X563700Y352400D02*
Y356900D01*
G01X560100Y391500D02*
Y389150D01*
X560200Y389050D01*
Y386500D01*
G01X578937Y407875D02*
X567126D01*
G01X555315D02*
X567126D01*
G01X560100Y396000D02*
X560800Y396700D01*
X564400D01*
G01X585000Y226500D02*
X587600Y223900D01*
X589953D01*
G01X576200Y351700D02*
Y356700D01*
G01Y346700D02*
Y342500D01*
G01Y361700D02*
X580200D01*
G01X576200Y356700D02*
X580300D01*
G01X576200Y366700D02*
X580100D01*
G01X576200Y375700D02*
X580300D01*
G01X576200Y385700D02*
Y380700D01*
G01D02*
X580300D01*
G01X576200Y375700D02*
Y380700D01*
G01X580300Y385700D02*
X576200D01*
G01Y390700D02*
X580300D01*
G01X590748Y407875D02*
X578937D01*
G01X599000Y92500D02*
Y94000D01*
X605660Y100660D01*
X608450D01*
G01X591400Y96500D02*
Y102500D01*
G01Y96500D02*
X588000D01*
G01X595600Y112500D02*
Y112600D01*
X599500Y116500D01*
G01X599450Y127063D02*
X592000D01*
G01X599450Y137063D02*
X593063D01*
X592000Y136000D01*
G01X596902Y190865D02*
Y190089D01*
X594003Y187190D01*
Y187000D01*
G01X589953Y228402D02*
X588098D01*
X586500Y230000D01*
G01X614370Y407875D02*
X602559D01*
G01D02*
X590748D01*
G01X614648Y127063D02*
X622000D01*
G01X614648Y137063D02*
X620937D01*
X622000Y136000D01*
G01X626550Y108340D02*
X628840D01*
X634000Y113500D01*
X637900D01*
G01D02*
Y116900D01*
G01X641050Y216142D02*
X636000D01*
G01X626989Y220184D02*
Y217063D01*
X625800Y215874D01*
G01X641050Y205906D02*
X633500D01*
G01X626989Y231484D02*
Y237989D01*
G01X622356Y301500D02*
X633500D01*
G01X642100Y108000D02*
X647000D01*
G01X642100D02*
Y102000D01*
G01D02*
Y96500D01*
G01Y113500D02*
X647000D01*
G54D116*
X614648Y127063D03*
Y137063D03*
Y147063D03*
Y157063D03*
Y167063D03*
Y177063D03*
G54D50*
X167800Y377600D03*
X164800Y415100D03*
X182200Y310500D03*
X184800Y326000D03*
X178200D03*
X174400Y377600D03*
X171400Y415100D03*
X188800Y310500D03*
X325500Y420200D03*
X328500Y382700D03*
X335100D03*
X332100Y420200D03*
X373200Y106000D03*
X379800D03*
X413400Y285500D03*
X420000D03*
X413400Y293600D03*
X420000D03*
X458800Y392700D03*
X465400D03*
X493300Y126400D03*
X499900D03*
X516200Y252100D03*
X508000Y253400D03*
X501400D03*
X527300Y124000D03*
X520700D03*
X522800Y252100D03*
X529800Y382700D03*
X548400Y86300D03*
X536400Y382700D03*
X563200Y85900D03*
X555000Y86300D03*
X565700Y161000D03*
X569800Y85900D03*
X572300Y161000D03*
G54D107*
X553600Y369369D03*
Y372913D03*
Y376456D03*
Y379999D03*
G54D23*
X52443Y100000D03*
X50357D03*
X48957Y157000D03*
X51043D03*
X49557Y216600D03*
X51643D03*
X51743Y268000D03*
X49657D03*
X123543Y379000D03*
X121457D03*
X126957D03*
X129043D03*
X147143Y390100D03*
X145057D03*
Y403100D03*
X147143D03*
X146643Y408600D03*
X144557D03*
X171457Y290000D03*
X173543D03*
X352757Y389200D03*
X354843D03*
Y394700D03*
X352757D03*
X352657Y412100D03*
X354743D03*
X394157Y277400D03*
X396243D03*
X495257Y277700D03*
X497343D03*
X529043Y272500D03*
X526957D03*
X543957Y63500D03*
X546043D03*
X548557Y391200D03*
X550643D03*
X578043Y60900D03*
X575957D03*
X571057Y371200D03*
X573143D03*
G54D41*
X126067Y104043D03*
Y184043D03*
Y264043D03*
X253967Y93443D03*
X265967D03*
X277867D03*
X286067Y104043D03*
Y264043D03*
G54D32*
X79932Y263049D03*
X77964D03*
Y269151D03*
X79932D03*
G54D14*
X11264Y152264D03*
X9000Y279000D03*
Y286000D03*
X17500Y91000D03*
X12500D03*
Y96000D03*
Y101000D03*
Y106000D03*
X19100Y148798D03*
X23600D03*
X28100D03*
X13620Y148720D03*
X13000Y157000D03*
X12500Y162000D03*
X17000Y204500D03*
X12500Y209500D03*
Y204500D03*
Y214500D03*
Y219500D03*
X11963Y266437D03*
X19000Y262500D03*
X24200Y262508D03*
X28700D03*
X12500Y261500D03*
X19900Y283000D03*
X15000Y279000D03*
X28700Y274300D03*
X13000Y273327D03*
X16000Y302500D03*
X28500Y302000D03*
X28000Y296500D03*
X16000Y297500D03*
Y307500D03*
X24100Y310900D03*
X18000Y314500D03*
X13000Y318700D03*
X11976Y323524D03*
X28000Y327000D03*
X44500Y73500D03*
X45500Y104390D03*
Y126000D03*
X41500Y127500D03*
X41409Y132591D03*
X45500Y161000D03*
X41600Y148798D03*
X32600Y148700D03*
X37100Y148798D03*
X45500Y182500D03*
X45000Y213000D03*
X46000Y219500D03*
X42000Y236800D03*
X40500Y262000D03*
X33200Y262508D03*
X43000Y255500D03*
X37400Y282900D03*
X29000Y291500D03*
X43000Y314500D03*
X33000D03*
X44500Y309000D03*
X39500D03*
X34500D03*
X35500Y327000D03*
X59600Y60200D03*
X55500Y59000D03*
X50500Y60228D03*
X51772Y73600D03*
X47600Y68900D03*
X60100Y73000D03*
X63500Y84500D03*
X57000Y83500D03*
X51500D03*
X47000Y100000D03*
X61400Y104900D03*
X50500Y104800D03*
X59000Y96500D03*
X62500Y100500D03*
X57500Y101500D03*
X56500Y113000D03*
X62500Y117000D03*
X48390Y128312D03*
X53740Y126000D03*
X51772Y130500D03*
X55922Y140543D03*
X46500Y133000D03*
X47500Y140500D03*
X53900Y157000D03*
X60600Y161200D03*
X60500Y152000D03*
X51400Y161600D03*
X54130Y152500D03*
X60600Y157000D03*
X48957Y153619D03*
X54500Y171000D03*
X62000Y199500D03*
X51772Y187987D03*
X53500Y183500D03*
X58000Y213500D03*
X54000D03*
X48000Y200500D03*
X53000D03*
X63000Y206000D03*
Y210500D03*
Y215000D03*
X49600Y213455D03*
X57500Y226500D03*
Y218500D03*
X51452Y219900D03*
X51772Y245074D03*
X53200Y240187D03*
X54590Y266870D03*
X48232Y264530D03*
X48500Y252500D03*
X55200Y253500D03*
X48500Y271500D03*
X52500Y278000D03*
X52800Y272000D03*
X63600Y291500D03*
X57500Y289000D03*
X62000Y307000D03*
X61489Y332329D03*
X62000Y323500D03*
X55000Y336000D03*
Y355400D03*
X63500Y359600D03*
X62500Y365000D03*
Y369000D03*
Y373000D03*
Y378000D03*
Y382000D03*
X60300Y407100D03*
Y401100D03*
Y395100D03*
Y413100D03*
X75500Y62000D03*
X64400Y70000D03*
X67700Y65000D03*
X66400Y77400D03*
X71500Y77000D03*
X66000Y91100D03*
X76400Y87200D03*
X76321Y78300D03*
X78500Y82250D03*
X69500Y100000D03*
X73500Y112500D03*
X67000Y109000D03*
X79000Y100500D03*
X74000D03*
X64500Y129500D03*
X67500Y114500D03*
X68000Y119000D03*
X73500D03*
X69500Y130000D03*
X74000D03*
X75000Y141700D03*
X64445Y168945D03*
X69000Y187500D03*
Y193000D03*
X69023Y198524D03*
X74593Y202207D03*
X71400Y221700D03*
X67500Y222900D03*
X67400Y227100D03*
X71400Y232900D03*
X64700Y251700D03*
X71500Y247800D03*
X68000Y235500D03*
X67700Y240200D03*
X72400Y264600D03*
X80148Y253648D03*
X69500Y257800D03*
X64248Y258000D03*
X64500Y296750D03*
X78000Y291500D03*
X79500Y308500D03*
X66000Y318500D03*
X79000Y315500D03*
X71000Y330500D03*
X78000D03*
X72000Y335000D03*
X66000Y323500D03*
X78635Y324492D03*
X79500Y341790D03*
Y348500D03*
X72000Y346300D03*
X73000Y365000D03*
X69500D03*
X66000D03*
X66500Y382000D03*
X70500D03*
X80700Y399200D03*
Y404200D03*
X71300D03*
Y399200D03*
X76000D03*
Y404200D03*
X71300Y394200D03*
X76000D03*
X80700D03*
X64300Y407600D03*
Y401600D03*
Y395600D03*
X66000Y419000D03*
X80500Y420500D03*
X80700Y409200D03*
X76000D03*
X71300D03*
X64300Y413600D03*
X88900Y67000D03*
X86000Y63100D03*
X84200Y75000D03*
X83300Y87100D03*
X82100Y79300D03*
X96500Y98000D03*
X92250Y97750D03*
X94500Y105000D03*
X89000Y110500D03*
X93500D03*
X90500Y105000D03*
X84000Y100500D03*
X87000Y130000D03*
Y120000D03*
X93500Y125000D03*
X87000Y125500D03*
X93500Y130000D03*
X86600Y141300D03*
X90500Y144500D03*
X95500Y145500D03*
X96500Y140000D03*
X91500D03*
X88400Y154900D03*
X93900Y155200D03*
X95200Y151000D03*
X88500Y149000D03*
X94500Y163000D03*
X98500Y159000D03*
X91000Y181500D03*
X88250Y177250D03*
X83500Y178000D03*
X97500Y172000D03*
X98500Y165500D03*
X92000Y173000D03*
X83500D03*
X95500Y192000D03*
X83500Y193000D03*
Y188500D03*
X90500D03*
X94500Y197000D03*
X90500Y193500D03*
X85750Y202750D03*
X97500Y214000D03*
X84500Y218000D03*
X95700Y227500D03*
X98500Y218500D03*
X93032Y246477D03*
X96000Y241000D03*
X85700Y236500D03*
X96500Y235500D03*
X87200Y258300D03*
X98700Y268300D03*
X98500Y256661D03*
X83200Y260300D03*
X86900Y267200D03*
X95900Y278900D03*
X94500Y299000D03*
X88500Y303000D03*
X95000Y291500D03*
X87500Y295500D03*
X94500Y312500D03*
X95000Y321500D03*
X95593Y333347D03*
X82500Y339000D03*
X82951Y327940D03*
X97500Y341000D03*
X95100Y351900D03*
X83000Y352500D03*
Y344500D03*
X95000D03*
X82800Y364600D03*
X94500Y373000D03*
Y369000D03*
Y364500D03*
X90500D03*
X86500D03*
X91500Y359500D03*
X83500Y360000D03*
X82800Y384600D03*
X94500Y380500D03*
X94000Y384500D03*
X90500D03*
X86500D03*
X94500Y376500D03*
X97800Y391800D03*
X85400Y404200D03*
Y399200D03*
Y394200D03*
X96800Y408100D03*
X92800D03*
Y402100D03*
X96800D03*
Y396100D03*
X92800D03*
X94000Y420000D03*
X83000Y417000D03*
X85400Y409200D03*
X96800Y414100D03*
X92800D03*
X111330Y59810D03*
X103800Y76240D03*
X99000Y175500D03*
Y188500D03*
Y197500D03*
Y206500D03*
Y201500D03*
Y260025D03*
X98800Y272400D03*
X112500Y302000D03*
X107500D03*
X112500Y290000D03*
X102500D03*
Y302000D03*
X104500Y305500D03*
X105410Y318500D03*
X115253Y306247D03*
X99000Y350000D03*
X101500Y341000D03*
X104019Y347425D03*
X103000Y351500D03*
X113000Y344500D03*
X114000Y352000D03*
X99500Y370000D03*
X103000Y364000D03*
X106500D03*
X110000D03*
X115500Y389000D03*
X104500Y377000D03*
X102500Y420000D03*
X119500Y57694D03*
X125000Y76500D03*
X126000Y72000D03*
X127500Y290500D03*
X117500Y290000D03*
X125095Y306095D03*
X129000Y321500D03*
X126000Y318000D03*
X129500Y328000D03*
X123500Y347500D03*
X130000Y349664D03*
X119000Y352000D03*
X124500D03*
X120000Y364500D03*
X129000Y365000D03*
Y370500D03*
X120000Y368000D03*
Y371500D03*
X132000Y379000D03*
X118500D03*
X132000Y375500D03*
X127000Y397061D03*
X117000Y397000D03*
X121169Y396892D03*
X150860Y67400D03*
X145000Y296500D03*
X141000Y298500D03*
X140100Y306900D03*
X135000Y312000D03*
X149500Y311034D03*
X140700Y320000D03*
X142130Y325630D03*
X146000Y334000D03*
X141916Y333916D03*
X140900Y355400D03*
X142000Y350000D03*
X148000Y370000D03*
X137000Y364000D03*
X145000Y359000D03*
X140123Y391604D03*
X135500Y383000D03*
Y390500D03*
X141000Y379500D03*
X148500Y380000D03*
X145000Y378000D03*
X140100Y395600D03*
X135500Y396000D03*
X135200Y408400D03*
X140000Y401000D03*
X135100Y412600D03*
X143500Y418000D03*
X153270Y58400D03*
X151200Y75191D03*
X160500Y75500D03*
Y71500D03*
X165000Y294000D03*
X166150Y304050D03*
X156800Y301100D03*
X156600Y295000D03*
X153500Y310500D03*
X156000Y320500D03*
Y316500D03*
X166700Y338800D03*
X151000Y324200D03*
X156000Y325000D03*
Y329000D03*
X159100Y350400D03*
Y354600D03*
X166700Y343800D03*
X151500Y370000D03*
Y358000D03*
X159100Y382600D03*
X163600Y378600D03*
X157900Y387400D03*
X158500Y405200D03*
X160582Y410000D03*
X160550Y413400D03*
X151700Y411300D03*
X173170Y70840D03*
X168500Y294000D03*
X169850Y298950D03*
X182600Y289500D03*
X179500Y294600D03*
X176500Y290000D03*
X178000Y309500D03*
X173800Y324100D03*
X178600Y378600D03*
Y374600D03*
X175100Y382600D03*
Y387100D03*
X174600Y401600D03*
Y406100D03*
X175000Y394500D03*
X177000Y398000D03*
X174600Y410600D03*
X176000Y416000D03*
X188900Y54960D03*
X192160Y77840D03*
X190000Y301500D03*
Y305500D03*
X189500Y319000D03*
X201700Y327900D03*
X189000Y326000D03*
X195900Y332500D03*
X191500Y413000D03*
X213500Y54000D03*
X208160Y73990D03*
X215000Y69000D03*
X220000D03*
X204770Y67780D03*
X207800Y83010D03*
X219200Y338800D03*
X205000Y348800D03*
Y353800D03*
X215000Y343800D03*
X219000Y348800D03*
X218000Y381100D03*
X219000Y392500D03*
X215500D03*
X216500Y396000D03*
X220000D03*
X217600Y415100D03*
X229582Y48918D03*
X223500Y58250D03*
X231000Y68000D03*
Y71500D03*
X228500Y75500D03*
Y79000D03*
X226500Y334000D03*
X222500Y324500D03*
X238000Y345000D03*
X225500Y347500D03*
X230000D03*
X228500Y382500D03*
X221500Y378500D03*
X226000D03*
X225000Y396000D03*
X221500Y415000D03*
X225600Y415100D03*
X229500Y415000D03*
X254000Y213500D03*
X241441Y215000D03*
X241900Y238800D03*
X249000Y290300D03*
X255400Y290100D03*
X247000Y344500D03*
X251000D03*
X255000D03*
X272330Y54871D03*
X259500Y54700D03*
Y70100D03*
X271000Y184500D03*
X269000Y215000D03*
X259000Y223000D03*
Y344500D03*
X282200Y179121D03*
X275260Y223000D03*
X280500Y224300D03*
X288000Y293000D03*
X288500Y317000D03*
X303500Y69400D03*
X296400Y70200D03*
X307500Y160500D03*
X303500Y164000D03*
X306500Y169500D03*
X298284Y175184D03*
X298500Y184500D03*
X300995Y187611D03*
X297772Y188694D03*
X292000Y294720D03*
X299500Y295500D03*
X301000Y312000D03*
X297000Y310500D03*
X301000Y317000D03*
X293700Y317300D03*
X309000Y164500D03*
X312500Y160500D03*
X320500Y170000D03*
X311000Y193500D03*
X312000Y217000D03*
X308967Y204000D03*
X324000Y227500D03*
X312000Y234400D03*
X324000Y220750D03*
X312500Y225400D03*
X311900Y229900D03*
Y243400D03*
X323500Y263000D03*
X311600Y252400D03*
X312000Y269000D03*
Y256500D03*
Y264500D03*
X314500Y276500D03*
X324000Y301000D03*
X312000Y295500D03*
X317500D03*
X321000D03*
X324500D03*
X310500Y321000D03*
X312500Y307500D03*
X310600Y326000D03*
X321899Y343000D03*
X325000Y363000D03*
X320000Y398500D03*
X323000Y401500D03*
X321300Y423600D03*
X324800Y415200D03*
X321300Y416700D03*
X324800Y410700D03*
X336000Y61060D03*
X340500Y63500D03*
Y87000D03*
X338000Y102500D03*
X338500Y213500D03*
X332550Y213550D03*
X341500Y233500D03*
X327923Y221577D03*
X335153Y217875D03*
X340953Y237000D03*
X330500Y265000D03*
X337500D03*
X328500Y258900D03*
X333500D03*
X338500Y259000D03*
X339500Y282000D03*
X332000Y301500D03*
X330500Y291500D03*
X341000Y304000D03*
X332500Y306500D03*
X328000D03*
X338000Y315000D03*
X341400Y323500D03*
X337000Y344000D03*
X326000Y374000D03*
X340500Y361300D03*
X332500D03*
X336500D03*
X325300Y387200D03*
X331500Y376000D03*
X338500D03*
X342000D03*
X339200Y380300D03*
X339300Y384000D03*
Y387700D03*
X340500Y391600D03*
X325300Y396200D03*
Y391700D03*
X336300Y423200D03*
Y415200D03*
Y419200D03*
X340800Y415200D03*
X349500Y61000D03*
X354500Y60920D03*
X345500Y87000D03*
X354000Y82500D03*
X344000Y103000D03*
X354000Y128000D03*
X351000Y130500D03*
X353500D03*
X356000D03*
X347500Y141500D03*
X350000D03*
X352500D03*
X355000D03*
X357000Y154200D03*
X353482Y154157D03*
X350085Y154300D03*
X350100Y169400D03*
X352600D03*
X357600D03*
X355100D03*
X347300Y179000D03*
X346500Y174000D03*
X344500Y181500D03*
X351200Y196600D03*
X349128Y186628D03*
X344000Y212000D03*
X350500Y229500D03*
X355500Y218000D03*
Y220500D03*
Y225500D03*
Y223000D03*
X351000Y233243D03*
X355000Y242500D03*
X354975Y247900D03*
X351000Y237000D03*
X358000Y261500D03*
X344500Y265000D03*
X343500Y258900D03*
X352500Y260000D03*
X348500D03*
X357680Y271780D03*
X357000Y295500D03*
X356000Y302300D03*
X349000Y303000D03*
Y295500D03*
X355500Y306500D03*
X346000D03*
X351000Y308000D03*
X355000Y337000D03*
X348418Y361300D03*
X344500D03*
X347700Y381600D03*
X347000Y391200D03*
X360000Y402400D03*
X359800Y397700D03*
X347600Y398800D03*
X348279Y405678D03*
X353000Y416500D03*
X350000Y419500D03*
X349500Y415000D03*
X346000Y416000D03*
X343700Y409900D03*
X348863Y410500D03*
X370500Y84000D03*
X376838Y100230D03*
X369310Y109500D03*
X369172Y102828D03*
X367000Y126000D03*
X374300Y129000D03*
X371800D03*
X362000Y123500D03*
Y128000D03*
X374300Y132000D03*
X371800D03*
X376500Y141000D03*
X374000D03*
X360500Y154500D03*
X374900Y154228D03*
X371400Y154300D03*
X367900Y154228D03*
X374600Y178200D03*
X363600Y176600D03*
X367600Y169300D03*
X364700Y169400D03*
X367400Y174400D03*
X373649Y185735D03*
X375000Y210000D03*
X369560Y213000D03*
X372060D03*
X367000D03*
X364500D03*
X367000Y232000D03*
X372500D03*
X377500Y218500D03*
Y221000D03*
Y226500D03*
Y223500D03*
X360500Y243000D03*
X367000Y241243D03*
X373500Y247000D03*
X365500Y246500D03*
X369500Y267500D03*
X375800Y255200D03*
X376500Y269000D03*
X365000Y268000D03*
X365500Y279500D03*
X362300Y286100D03*
X365800D03*
X370000Y276000D03*
X374500D03*
X374800Y291100D03*
X370300D03*
X361500Y296100D03*
X365800Y291100D03*
X362100Y291000D03*
X361400Y301500D03*
Y305800D03*
Y309900D03*
X365500Y305900D03*
X375500Y309200D03*
X371000Y326000D03*
X370000Y337000D03*
Y332500D03*
X366000Y350850D03*
X360700Y406200D03*
X369000Y413500D03*
X374500Y418500D03*
X363100Y418300D03*
X360311Y409880D03*
X363100Y422800D03*
X364500Y413500D03*
X382286Y86214D03*
X384000Y102980D03*
Y109500D03*
X379000Y141000D03*
X382000Y142000D03*
X378400Y154300D03*
X379800Y177100D03*
X380000Y210000D03*
Y204500D03*
X384091Y200091D03*
X394000Y223500D03*
X383000Y232500D03*
X390000D03*
X379500Y237500D03*
X391900Y246800D03*
X386000D03*
X380100D03*
X386000Y259250D03*
X378000Y273500D03*
X389400Y281100D03*
X378000Y281000D03*
X382200D03*
X394800Y281300D03*
X388650Y292650D03*
X378000Y293200D03*
X383000D03*
X393300Y312500D03*
X383000Y323500D03*
X390000Y338500D03*
X392500Y329100D03*
Y323900D03*
X383000Y341500D03*
X384300Y368700D03*
X383900Y372600D03*
X381000Y365000D03*
X386500D03*
X389500Y370000D03*
X395000D03*
Y360000D03*
Y382000D03*
X383900Y384600D03*
X379500Y381000D03*
Y375800D03*
Y417500D03*
X407000Y120000D03*
X399500D03*
X399000Y221407D03*
Y225000D03*
X407500D03*
X397800Y246800D03*
X403700D03*
X409300D03*
X397800Y259300D03*
X403700D03*
X400000Y265500D03*
X399800Y278400D03*
X409100Y281300D03*
X409300Y286300D03*
X402000Y303000D03*
X409200Y291700D03*
X396981Y304482D03*
X407500Y300500D03*
X402500Y308000D03*
X397500Y312900D03*
X407500Y305000D03*
X397300Y320700D03*
X408500Y316500D03*
Y321998D03*
Y311000D03*
X408000Y327000D03*
X398000Y336500D03*
X410000Y338000D03*
X398000Y352000D03*
X406610Y353410D03*
X411840Y353620D03*
X410000Y358543D03*
X409000Y371339D03*
X409650Y403950D03*
X412350Y401250D03*
Y397150D03*
X409650Y394450D03*
X422000Y77500D03*
X423000Y72950D03*
X417500Y75000D03*
X420500Y82000D03*
X413500Y88500D03*
X425000Y87700D03*
X423000Y100500D03*
X427800Y100300D03*
X429400Y107500D03*
X429000Y123500D03*
X422000D03*
X418500Y117000D03*
X415000Y123500D03*
X425400Y229600D03*
X420500Y229500D03*
X414900Y229800D03*
X423000Y235400D03*
X416100D03*
X420900Y246800D03*
X415000D03*
X420900Y259000D03*
X429000Y274000D03*
X424900Y284300D03*
X423900Y278500D03*
X424900Y292900D03*
X413000Y300500D03*
X429442Y310075D03*
X417500Y337000D03*
Y352000D03*
X422500Y354500D03*
X428500Y346000D03*
X413500Y373500D03*
X419000D03*
X420500Y366000D03*
X425000Y381000D03*
X420500D03*
X419150Y394450D03*
X416450Y401250D03*
Y397150D03*
X419150Y403950D03*
X423500Y415500D03*
X434500Y77000D03*
X441400Y78100D03*
X433500Y100500D03*
X444200D03*
X431000Y116500D03*
X444000Y226000D03*
X436500Y233000D03*
X443500Y231500D03*
X444000Y250000D03*
X436500Y237500D03*
X439500Y250000D03*
X435000Y250500D03*
X443500Y236500D03*
X439500Y266500D03*
X444000Y263000D03*
X440000Y278500D03*
X434600Y278300D03*
X435500Y274500D03*
X445600Y278300D03*
X438150Y283800D03*
X447000Y283000D03*
X433050Y291400D03*
X446000Y294000D03*
X439000Y302000D03*
X434500D03*
X433000Y314320D03*
X435143Y306643D03*
X447000Y321998D03*
X440000Y332500D03*
X434000Y328000D03*
X447200Y347500D03*
X433000Y353500D03*
X433500Y366500D03*
X433382Y360466D03*
X438500Y364500D03*
X430000Y386500D03*
X446000Y374500D03*
X438400Y382400D03*
X430000Y381000D03*
X431000Y406500D03*
Y416000D03*
Y411500D03*
X460000Y76000D03*
X448430Y89540D03*
X463500Y86500D03*
Y92000D03*
X458500Y86500D03*
X450000Y108200D03*
X454600Y108500D03*
X448500Y100500D03*
X462500Y117000D03*
X461996Y162690D03*
X462000Y224500D03*
X461000Y234500D03*
X457500Y227500D03*
Y223500D03*
X449000Y232500D03*
Y227500D03*
X461000Y230000D03*
X462000Y250000D03*
X448500Y237500D03*
X457500Y250000D03*
X448500D03*
X457500Y237400D03*
X453000Y250000D03*
X457000Y258500D03*
X459500Y262000D03*
X461500Y268409D03*
X460000Y284500D03*
Y289500D03*
X460800Y294200D03*
X461000Y302500D03*
X464500Y298500D03*
X456500Y305500D03*
X454000Y312500D03*
X448500Y311500D03*
X461500Y311000D03*
X451000Y306500D03*
X459500Y322000D03*
X459000Y326000D03*
X450900Y330900D03*
X450500Y368500D03*
X453500Y381500D03*
X454000Y393500D03*
Y397000D03*
X450000Y407000D03*
Y416500D03*
Y411500D03*
X481000Y70700D03*
X479500Y92500D03*
X478000Y78000D03*
X482000Y83500D03*
X465500Y78500D03*
X475500Y82500D03*
X470500D03*
X466500Y110400D03*
X471200Y115700D03*
X481600Y125800D03*
X476800Y120700D03*
X479867Y138867D03*
X473807Y154816D03*
X465933Y162690D03*
X473807Y150879D03*
X481500Y182016D03*
X481000Y172500D03*
X479246Y178464D03*
X477500Y170500D03*
X478000Y198000D03*
X481500Y193000D03*
X482000Y212500D03*
X480288Y203788D03*
X471000Y239000D03*
X477000D03*
X471000Y259200D03*
X477500Y259000D03*
X468500Y264500D03*
Y270000D03*
X467000Y355500D03*
X471000Y347000D03*
X478500Y346000D03*
X481000Y341000D03*
X471400Y363300D03*
X470500Y391000D03*
X493700Y79161D03*
X496000Y85000D03*
X482800Y110300D03*
X489400Y126300D03*
X493300Y121500D03*
X483000Y133000D03*
X485000Y154000D03*
X497500Y148500D03*
X491000Y154000D03*
X491500Y148500D03*
X497000Y154000D03*
X496000Y163000D03*
Y167500D03*
Y179258D03*
X484000Y166000D03*
X497000Y175000D03*
X485033Y174934D03*
X498060Y185500D03*
X496500Y192500D03*
X483871Y198241D03*
X496500Y197500D03*
X484000Y185500D03*
X497500Y214000D03*
X496000Y205500D03*
X485000Y202739D03*
X490500Y216750D03*
X492500Y226000D03*
X497500D03*
X497100Y244700D03*
X497200Y240600D03*
X492300Y240800D03*
X483100Y272800D03*
X492500Y272200D03*
X491800Y277700D03*
X497000Y341000D03*
X495000Y346000D03*
X483501D03*
X488500D03*
X504000Y64500D03*
X508500D03*
X513200Y66000D03*
X503005Y99494D03*
X508000Y105500D03*
Y110500D03*
Y115500D03*
X503860Y124150D03*
X503900Y128690D03*
X503950Y143000D03*
X514500Y144000D03*
X503950Y133500D03*
X503000Y155000D03*
X503500Y149000D03*
X514500Y151000D03*
Y148000D03*
Y154000D03*
Y157000D03*
X501500Y192500D03*
X507000D03*
Y188500D03*
X515500Y201000D03*
X513000Y210500D03*
X511500Y206500D03*
X513500Y215500D03*
X509000D03*
X512100Y249500D03*
X507100Y240700D03*
X512100D03*
Y244700D03*
X502200Y240700D03*
X512100Y262500D03*
X512300Y254400D03*
X512200Y258700D03*
X512650Y268150D03*
X501000Y263500D03*
X511900Y276200D03*
X508950Y273250D03*
X506100Y280600D03*
X509000Y340500D03*
X504500D03*
X514000Y374000D03*
X505000Y379500D03*
X504500Y376000D03*
X507500Y394500D03*
X503500D03*
X521500Y60000D03*
X529500Y60500D03*
X526500Y67500D03*
X519500Y75500D03*
X533000Y87000D03*
Y82000D03*
X519500Y81500D03*
X520000Y87000D03*
X524900Y99000D03*
X522500Y114500D03*
X533500Y124500D03*
X534000Y160500D03*
X517000Y212500D03*
X533200Y220000D03*
X529800Y223000D03*
X528710Y227500D03*
X534000Y231500D03*
X525400Y247000D03*
X522000D03*
X534500Y253600D03*
X530350Y257480D03*
X524300Y261700D03*
X523900Y257100D03*
X532500Y272500D03*
X523600Y281100D03*
X531000Y285500D03*
X526000Y295500D03*
X532900Y318900D03*
X527600D03*
X519000Y307500D03*
X532400Y340600D03*
Y345600D03*
X527100Y340600D03*
Y345600D03*
X517500Y374000D03*
X532200Y377700D03*
X523700Y384100D03*
X528200Y377700D03*
X523700D03*
X518000Y382500D03*
X527500Y389100D03*
X530000Y406500D03*
X532100Y399000D03*
X527500Y397100D03*
Y393100D03*
X525176Y411925D03*
X522100Y416500D03*
X551500Y59597D03*
X543957Y60543D03*
X537000Y69000D03*
X549000Y63500D03*
X544500Y79500D03*
X549000Y78223D03*
X544300Y87100D03*
X549400Y81600D03*
X536500Y84500D03*
Y79000D03*
X541000Y96000D03*
X534500Y130000D03*
Y136500D03*
X534600Y148300D03*
Y152000D03*
X544000Y159000D03*
X543520Y174970D03*
X542270Y169900D03*
X539770Y174900D03*
Y169900D03*
Y172400D03*
X542270D03*
X542500Y189500D03*
X538500D03*
X540900Y201500D03*
X543500Y205000D03*
X536900Y201500D03*
X545800Y216500D03*
X541000Y216400D03*
X540600Y234600D03*
X537500Y232000D03*
X548300Y222600D03*
X546500Y240500D03*
X549000Y267500D03*
X551700Y256300D03*
X541000Y281500D03*
X539500Y292000D03*
X541346Y303507D03*
X542000Y296450D03*
X537500Y304000D03*
X538600Y318900D03*
X538100Y340600D03*
Y345600D03*
X539000Y370000D03*
X539300Y365100D03*
X539000Y360000D03*
X543000Y370000D03*
X543300Y365100D03*
X543000Y360000D03*
X548557Y387700D03*
X540600Y386300D03*
X538500Y407875D03*
X543000Y396700D03*
X548829Y416329D03*
X548500Y411000D03*
X538558Y413779D03*
X550369Y427558D03*
X538558D03*
X562500Y74600D03*
X560650Y70450D03*
X559941Y62120D03*
X563341Y62102D03*
X564350Y65350D03*
X559000Y85000D03*
X560200Y81500D03*
X559000Y88800D03*
X565933Y102000D03*
X562533Y102001D03*
X553000Y108500D03*
X558000Y161500D03*
X568700Y204300D03*
X564700Y204400D03*
X554600Y202400D03*
X558900Y202500D03*
X566950Y220000D03*
X553800Y240200D03*
X560000Y240000D03*
X565400Y244700D03*
X562000Y254870D03*
X554400Y267500D03*
X561700Y320300D03*
X556700D03*
X562500Y336100D03*
Y326100D03*
X562000Y331600D03*
X566000Y347000D03*
X563700Y352400D03*
X560000Y342100D03*
X568100Y366400D03*
Y361700D03*
X568326Y371200D03*
X563800Y390700D03*
X564500Y379000D03*
X560200Y386500D03*
X567500D03*
X568600Y376000D03*
Y380700D03*
X560000Y401000D03*
X564400Y396700D03*
X567500Y403000D03*
X555000Y402000D03*
X567126Y417500D03*
X555315D03*
X562180Y413779D03*
Y427558D03*
X580500Y65800D03*
X580643Y60900D03*
X585900Y79600D03*
X580000Y104800D03*
X576500Y98000D03*
X586500Y107000D03*
Y112500D03*
X576459Y161971D03*
X575072Y165500D03*
X580500Y194500D03*
X583000Y192000D03*
X573200Y204300D03*
X586500Y230000D03*
X571000Y217900D03*
X576500Y219700D03*
X569943Y223300D03*
X585000Y226500D03*
X576000Y246500D03*
X578900Y236600D03*
X581500Y267000D03*
X581400Y292250D03*
X583000Y297000D03*
X580300Y356700D03*
X576300Y371200D03*
X580200Y361700D03*
X580100Y366700D03*
X580300Y380700D03*
Y375700D03*
Y385700D03*
Y390700D03*
X571800Y396500D03*
X576900Y403100D03*
X578937Y417500D03*
X572500Y413500D03*
X584000Y421900D03*
X573991Y427558D03*
X599000Y92500D03*
X588000Y96500D03*
X600850Y112350D03*
X592000Y127063D03*
X599500Y116500D03*
X592000Y136000D03*
Y141000D03*
Y146000D03*
Y163000D03*
Y151500D03*
Y157063D03*
Y173000D03*
Y178000D03*
Y168000D03*
X587000Y184000D03*
X597703Y187000D03*
X587500Y190000D03*
X594003Y187000D03*
X602500Y183000D03*
X601550Y208450D03*
X596450Y210350D03*
X601953Y218853D03*
X595500Y239000D03*
X590650Y245680D03*
X604000Y254500D03*
X591000Y271500D03*
Y278500D03*
Y291500D03*
X602500Y404000D03*
X591000D03*
X604000Y398000D03*
X597500Y421900D03*
X602559Y417500D03*
X590748Y418725D03*
X597613Y413779D03*
Y427558D03*
X616500Y194874D03*
X606902Y186000D03*
X610500Y190500D03*
X614100Y224100D03*
X610500Y227000D03*
X614100Y236400D03*
X618650Y249300D03*
X609500Y254500D03*
X614500Y398000D03*
Y403500D03*
X614370Y417500D03*
X609424Y413779D03*
Y427558D03*
X633500Y108000D03*
Y102000D03*
Y96500D03*
X637900Y116900D03*
X622000Y127063D03*
Y136000D03*
Y141500D03*
Y146500D03*
Y162000D03*
Y151600D03*
Y157000D03*
Y181500D03*
Y175500D03*
X622035Y167063D03*
X633500Y196874D03*
X628500Y189500D03*
X636000Y216142D03*
X627500Y205374D03*
X626989Y237989D03*
X633000Y286500D03*
X633500Y301500D03*
X647000Y108000D03*
Y113500D03*
G54D126*
G01X329433Y-125500D02*
Y-133000D01*
X333167D01*
G01X340480D02*
Y-128000D01*
G01Y-128875D02*
X340107Y-128375D01*
X339547Y-128125D01*
X338893Y-128000D01*
X338240Y-128250D01*
X337680Y-128750D01*
X337307Y-129500D01*
X337120Y-130500D01*
X337307Y-131500D01*
X337680Y-132250D01*
X338240Y-132750D01*
X338893Y-133000D01*
X339547Y-132875D01*
X340107Y-132500D01*
X340480Y-132000D01*
G01X344340Y-135250D02*
X344900Y-135500D01*
X345647Y-135250D01*
X346113Y-134750D01*
X346487Y-134125D01*
X347047Y-132125D01*
X348260Y-128000D01*
G01X345273D02*
X347047Y-132125D01*
G01X352400Y-129625D02*
X355387D01*
X355107Y-128750D01*
X354640Y-128250D01*
X353987Y-128000D01*
X353333Y-128125D01*
X352773Y-128500D01*
X352400Y-129375D01*
X352213Y-130125D01*
Y-130875D01*
X352400Y-131625D01*
X352867Y-132375D01*
X353427Y-132875D01*
X354080Y-133000D01*
X354733Y-132750D01*
X355387Y-132000D01*
G01X359993Y-133000D02*
Y-128000D01*
G01Y-129000D02*
X360460Y-128500D01*
X360927Y-128125D01*
X361580Y-128000D01*
X362047Y-128125D01*
X362607Y-128500D01*
G01X368800Y-133250D02*
X368613Y-133125D01*
Y-132875D01*
X368800Y-132750D01*
X368987Y-132875D01*
Y-133125D01*
X368800Y-133250D01*
G01Y-129875D02*
X368613Y-129750D01*
Y-129500D01*
X368800Y-129375D01*
X368987Y-129500D01*
Y-129750D01*
X368800Y-129875D01*
G01X336747Y-120500D02*
Y-113000D01*
X338613D01*
X339360Y-113375D01*
X339920Y-113875D01*
X340387Y-114625D01*
X340760Y-115500D01*
X340853Y-116750D01*
X340760Y-118000D01*
X340387Y-118875D01*
X339920Y-119625D01*
X339360Y-120125D01*
X338613Y-120500D01*
X336747D01*
G01X347980D02*
Y-115500D01*
G01Y-116375D02*
X347607Y-115875D01*
X347047Y-115625D01*
X346393Y-115500D01*
X345740Y-115750D01*
X345180Y-116250D01*
X344807Y-117000D01*
X344620Y-118000D01*
X344807Y-119000D01*
X345180Y-119750D01*
X345740Y-120250D01*
X346393Y-120500D01*
X347047Y-120375D01*
X347607Y-120000D01*
X347980Y-119500D01*
G01X353800Y-113000D02*
Y-120500D01*
G01X352493Y-115500D02*
X355107D01*
G01X359900Y-117125D02*
X362887D01*
X362607Y-116250D01*
X362140Y-115750D01*
X361487Y-115500D01*
X360833Y-115625D01*
X360273Y-116000D01*
X359900Y-116875D01*
X359713Y-117625D01*
Y-118375D01*
X359900Y-119125D01*
X360367Y-119875D01*
X360927Y-120375D01*
X361580Y-120500D01*
X362233Y-120250D01*
X362887Y-119500D01*
G01X368800Y-120750D02*
X368613Y-120625D01*
Y-120375D01*
X368800Y-120250D01*
X368987Y-120375D01*
Y-120625D01*
X368800Y-120750D01*
G01Y-117375D02*
X368613Y-117250D01*
Y-117000D01*
X368800Y-116875D01*
X368987Y-117000D01*
Y-117250D01*
X368800Y-117375D01*
G01X382027Y-114250D02*
X382587Y-113500D01*
X383240Y-113125D01*
X383987Y-113000D01*
X384920Y-113250D01*
X385573Y-113875D01*
X385760Y-114625D01*
X385667Y-115375D01*
X385293Y-116000D01*
X383427Y-117250D01*
X382587Y-118125D01*
X382027Y-119375D01*
X381840Y-120500D01*
X385760D01*
G01X391300Y-113000D02*
X390553Y-113250D01*
X389993Y-113875D01*
X389620Y-114625D01*
X389340Y-115625D01*
X389247Y-116750D01*
X389340Y-117875D01*
X389620Y-118875D01*
X389993Y-119625D01*
X390553Y-120250D01*
X391300Y-120500D01*
X392047Y-120250D01*
X392607Y-119625D01*
X392980Y-118875D01*
X393260Y-117875D01*
X393353Y-116750D01*
X393260Y-115625D01*
X392980Y-114625D01*
X392607Y-113875D01*
X392047Y-113250D01*
X391300Y-113000D01*
G01X397027Y-114250D02*
X397587Y-113500D01*
X398240Y-113125D01*
X398987Y-113000D01*
X399920Y-113250D01*
X400573Y-113875D01*
X400760Y-114625D01*
X400667Y-115375D01*
X400293Y-116000D01*
X398427Y-117250D01*
X397587Y-118125D01*
X397027Y-119375D01*
X396840Y-120500D01*
X400760D01*
G01X404527Y-114250D02*
X405087Y-113500D01*
X405740Y-113125D01*
X406487Y-113000D01*
X407420Y-113250D01*
X408073Y-113875D01*
X408260Y-114625D01*
X408167Y-115375D01*
X407793Y-116000D01*
X405927Y-117250D01*
X405087Y-118125D01*
X404527Y-119375D01*
X404340Y-120500D01*
X408260D01*
G01X412587Y-118000D02*
X415013D01*
G01X421300Y-113000D02*
X420553Y-113250D01*
X419993Y-113875D01*
X419620Y-114625D01*
X419340Y-115625D01*
X419247Y-116750D01*
X419340Y-117875D01*
X419620Y-118875D01*
X419993Y-119625D01*
X420553Y-120250D01*
X421300Y-120500D01*
X422047Y-120250D01*
X422607Y-119625D01*
X422980Y-118875D01*
X423260Y-117875D01*
X423353Y-116750D01*
X423260Y-115625D01*
X422980Y-114625D01*
X422607Y-113875D01*
X422047Y-113250D01*
X421300Y-113000D01*
G01X427027Y-114250D02*
X427587Y-113500D01*
X428240Y-113125D01*
X428987Y-113000D01*
X429920Y-113250D01*
X430573Y-113875D01*
X430760Y-114625D01*
X430667Y-115375D01*
X430293Y-116000D01*
X428427Y-117250D01*
X427587Y-118125D01*
X427027Y-119375D01*
X426840Y-120500D01*
X430760D01*
G01X435087Y-118000D02*
X437513D01*
G01X442027Y-114250D02*
X442587Y-113500D01*
X443240Y-113125D01*
X443987Y-113000D01*
X444920Y-113250D01*
X445573Y-113875D01*
X445760Y-114625D01*
X445667Y-115375D01*
X445293Y-116000D01*
X443427Y-117250D01*
X442587Y-118125D01*
X442027Y-119375D01*
X441840Y-120500D01*
X445760D01*
G01X449247Y-119375D02*
X449807Y-120000D01*
X450460Y-120375D01*
X451300Y-120500D01*
X452140Y-120250D01*
X452793Y-119750D01*
X453260Y-118875D01*
X453353Y-117875D01*
X453167Y-116875D01*
X452700Y-116250D01*
X452047Y-115750D01*
X451393Y-115625D01*
X450740Y-115750D01*
X449900Y-116250D01*
X450180Y-113000D01*
X452700D01*
G01X336933Y-108000D02*
Y-100500D01*
X339267D01*
X340013Y-100875D01*
X340480Y-101375D01*
X340667Y-102375D01*
X340480Y-103375D01*
X339920Y-104000D01*
X339267Y-104375D01*
X336933D01*
G01X339267D02*
X340667Y-108000D01*
G01X344900Y-104625D02*
X347887D01*
X347607Y-103750D01*
X347140Y-103250D01*
X346487Y-103000D01*
X345833Y-103125D01*
X345273Y-103500D01*
X344900Y-104375D01*
X344713Y-105125D01*
Y-105875D01*
X344900Y-106625D01*
X345367Y-107375D01*
X345927Y-107875D01*
X346580Y-108000D01*
X347233Y-107750D01*
X347887Y-107000D01*
G01X352120Y-103000D02*
X353800Y-108000D01*
X355480Y-103000D01*
G01X368800Y-108250D02*
X368613Y-108125D01*
Y-107875D01*
X368800Y-107750D01*
X368987Y-107875D01*
Y-108125D01*
X368800Y-108250D01*
G01Y-104875D02*
X368613Y-104750D01*
Y-104500D01*
X368800Y-104375D01*
X368987Y-104500D01*
Y-104750D01*
X368800Y-104875D01*
G01X383800Y-100500D02*
X383053Y-100750D01*
X382493Y-101375D01*
X382120Y-102125D01*
X381840Y-103125D01*
X381747Y-104250D01*
X381840Y-105375D01*
X382120Y-106375D01*
X382493Y-107125D01*
X383053Y-107750D01*
X383800Y-108000D01*
X384547Y-107750D01*
X385107Y-107125D01*
X385480Y-106375D01*
X385760Y-105375D01*
X385853Y-104250D01*
X385760Y-103125D01*
X385480Y-102125D01*
X385107Y-101375D01*
X384547Y-100750D01*
X383800Y-100500D01*
G01X391300Y-108000D02*
Y-100500D01*
X390180Y-102000D01*
G01Y-108000D02*
X392420D01*
G01X336933Y-95500D02*
Y-88000D01*
X339173D01*
X339920Y-88375D01*
X340480Y-89250D01*
X340667Y-90250D01*
X340480Y-91250D01*
X340013Y-92000D01*
X339173Y-92375D01*
X336933D01*
G01X344620Y-95750D02*
X347980Y-88000D01*
G01X351653Y-95500D02*
Y-88000D01*
X355947Y-95500D01*
Y-88000D01*
G01X368800Y-95750D02*
X368613Y-95625D01*
Y-95375D01*
X368800Y-95250D01*
X368987Y-95375D01*
Y-95625D01*
X368800Y-95750D01*
G01Y-92375D02*
X368613Y-92250D01*
Y-92000D01*
X368800Y-91875D01*
X368987Y-92000D01*
Y-92250D01*
X368800Y-92375D01*
G01X381933Y-95500D02*
Y-88000D01*
X384267D01*
X385013Y-88375D01*
X385480Y-88875D01*
X385667Y-89875D01*
X385480Y-90875D01*
X384920Y-91500D01*
X384267Y-91875D01*
X381933D01*
G01X384267D02*
X385667Y-95500D01*
G01X392420D02*
Y-88000D01*
X388967Y-93375D01*
X393633D01*
G01X398800Y-88000D02*
X398053Y-88250D01*
X397493Y-88875D01*
X397120Y-89625D01*
X396840Y-90625D01*
X396747Y-91750D01*
X396840Y-92875D01*
X397120Y-93875D01*
X397493Y-94625D01*
X398053Y-95250D01*
X398800Y-95500D01*
X399547Y-95250D01*
X400107Y-94625D01*
X400480Y-93875D01*
X400760Y-92875D01*
X400853Y-91750D01*
X400760Y-90625D01*
X400480Y-89625D01*
X400107Y-88875D01*
X399547Y-88250D01*
X398800Y-88000D01*
G01X406300D02*
X405553Y-88250D01*
X404993Y-88875D01*
X404620Y-89625D01*
X404340Y-90625D01*
X404247Y-91750D01*
X404340Y-92875D01*
X404620Y-93875D01*
X404993Y-94625D01*
X405553Y-95250D01*
X406300Y-95500D01*
X407047Y-95250D01*
X407607Y-94625D01*
X407980Y-93875D01*
X408260Y-92875D01*
X408353Y-91750D01*
X408260Y-90625D01*
X407980Y-89625D01*
X407607Y-88875D01*
X407047Y-88250D01*
X406300Y-88000D01*
G01X412027Y-92375D02*
X412680Y-91500D01*
X413240Y-91000D01*
X413987Y-90750D01*
X414640Y-91000D01*
X415107Y-91500D01*
X415480Y-92250D01*
X415573Y-93125D01*
X415480Y-93875D01*
X415107Y-94625D01*
X414547Y-95250D01*
X413893Y-95500D01*
X413147Y-95250D01*
X412493Y-94500D01*
X412120Y-93375D01*
X412027Y-92125D01*
X412213Y-90500D01*
X412493Y-89625D01*
X412960Y-88750D01*
X413613Y-88125D01*
X414267Y-88000D01*
X414920Y-88250D01*
X415387Y-88875D01*
G01X420087Y-93000D02*
X422513D01*
G01X429547Y-91500D02*
X429920Y-91125D01*
X430200Y-90500D01*
X430387Y-89625D01*
X430200Y-88875D01*
X429827Y-88375D01*
X429173Y-88000D01*
X426653D01*
Y-95500D01*
X429733D01*
X430387Y-95000D01*
X430760Y-94250D01*
X430947Y-93375D01*
X430760Y-92500D01*
X430200Y-91750D01*
X429547Y-91500D01*
X426653D01*
G01X436300Y-88000D02*
X435553Y-88250D01*
X434993Y-88875D01*
X434620Y-89625D01*
X434340Y-90625D01*
X434247Y-91750D01*
X434340Y-92875D01*
X434620Y-93875D01*
X434993Y-94625D01*
X435553Y-95250D01*
X436300Y-95500D01*
X437047Y-95250D01*
X437607Y-94625D01*
X437980Y-93875D01*
X438260Y-92875D01*
X438353Y-91750D01*
X438260Y-90625D01*
X437980Y-89625D01*
X437607Y-88875D01*
X437047Y-88250D01*
X436300Y-88000D01*
G01X443800D02*
X443053Y-88250D01*
X442493Y-88875D01*
X442120Y-89625D01*
X441840Y-90625D01*
X441747Y-91750D01*
X441840Y-92875D01*
X442120Y-93875D01*
X442493Y-94625D01*
X443053Y-95250D01*
X443800Y-95500D01*
X444547Y-95250D01*
X445107Y-94625D01*
X445480Y-93875D01*
X445760Y-92875D01*
X445853Y-91750D01*
X445760Y-90625D01*
X445480Y-89625D01*
X445107Y-88875D01*
X444547Y-88250D01*
X443800Y-88000D01*
G01X451300D02*
X450553Y-88250D01*
X449993Y-88875D01*
X449620Y-89625D01*
X449340Y-90625D01*
X449247Y-91750D01*
X449340Y-92875D01*
X449620Y-93875D01*
X449993Y-94625D01*
X450553Y-95250D01*
X451300Y-95500D01*
X452047Y-95250D01*
X452607Y-94625D01*
X452980Y-93875D01*
X453260Y-92875D01*
X453353Y-91750D01*
X453260Y-90625D01*
X452980Y-89625D01*
X452607Y-88875D01*
X452047Y-88250D01*
X451300Y-88000D01*
G01X458800Y-95500D02*
Y-88000D01*
X457680Y-89500D01*
G01Y-95500D02*
X459920D01*
G01X465087Y-93000D02*
X467513D01*
G01X473800Y-88000D02*
X473053Y-88250D01*
X472493Y-88875D01*
X472120Y-89625D01*
X471840Y-90625D01*
X471747Y-91750D01*
X471840Y-92875D01*
X472120Y-93875D01*
X472493Y-94625D01*
X473053Y-95250D01*
X473800Y-95500D01*
X474547Y-95250D01*
X475107Y-94625D01*
X475480Y-93875D01*
X475760Y-92875D01*
X475853Y-91750D01*
X475760Y-90625D01*
X475480Y-89625D01*
X475107Y-88875D01*
X474547Y-88250D01*
X473800Y-88000D01*
G01X479527Y-89250D02*
X480087Y-88500D01*
X480740Y-88125D01*
X481487Y-88000D01*
X482420Y-88250D01*
X483073Y-88875D01*
X483260Y-89625D01*
X483167Y-90375D01*
X482793Y-91000D01*
X480927Y-92250D01*
X480087Y-93125D01*
X479527Y-94375D01*
X479340Y-95500D01*
X483260D01*
G54D42*
X129831Y385154D03*
X121169D03*
Y391846D03*
X129831D03*
G54D108*
X555607Y363305D03*
G54D117*
X634055Y334449D03*
Y367519D03*
G54D24*
X55600Y165000D03*
X51400D03*
X61900Y279000D03*
X63100Y329000D03*
X58900D03*
X77900Y110000D03*
Y105000D03*
Y120000D03*
Y125000D03*
Y115000D03*
Y130000D03*
X74547Y179500D03*
X78747D03*
X74547Y175000D03*
X78747D03*
X74547Y193000D03*
X78747D03*
X74547Y197500D03*
X78747D03*
X74547Y188500D03*
X78747D03*
X74547Y184000D03*
X78747D03*
X68448Y266400D03*
X64248D03*
Y261400D03*
X68448D03*
X71400Y279000D03*
X75600D03*
X64248Y270900D03*
X68448D03*
X66100Y279000D03*
X70400Y320000D03*
X74600D03*
X70400Y324500D03*
X74600D03*
X82100Y110000D03*
Y105000D03*
Y120000D03*
Y125000D03*
Y115000D03*
Y130000D03*
X90700Y258048D03*
X94900D03*
X95048Y268300D03*
X90848D03*
X95100Y272800D03*
X90900D03*
X121570Y61360D03*
X117370D03*
Y65860D03*
X121570D03*
X117370Y75360D03*
X121570D03*
X117370Y70860D03*
X121570D03*
X130850Y65800D03*
Y61300D03*
X130870Y70800D03*
Y75300D03*
X122900Y375000D03*
X127100D03*
X135050Y65800D03*
Y61300D03*
X135070Y70800D03*
Y75300D03*
X148400Y295000D03*
X142500Y385100D03*
X146700D03*
X143500Y399100D03*
X147700D03*
X143500Y394600D03*
X147700D03*
Y414200D03*
X143500D03*
X152600Y295000D03*
X167000Y384100D03*
X165000Y409100D03*
X182400Y304000D03*
X181900Y319000D03*
X171200Y384100D03*
X169200Y409100D03*
X186600Y304000D03*
X186100Y319000D03*
X263700Y60500D03*
X259500D03*
Y65500D03*
X263700D03*
X289500Y320600D03*
Y325900D03*
X289600Y333200D03*
X299600Y57441D03*
X295400D03*
X299720Y66780D03*
X295520D03*
X299700Y62100D03*
X295500D03*
X293700Y320600D03*
Y325900D03*
X293800Y333200D03*
X312400Y164500D03*
X316600D03*
X312300Y180000D03*
X316500D03*
X316600Y169500D03*
X312400D03*
X312300Y175000D03*
X316500D03*
X316800Y196500D03*
X321000D03*
X316100Y189500D03*
X311900D03*
X316100Y185000D03*
X311900D03*
X316800Y201500D03*
X321000D03*
X316800Y206000D03*
X321000D03*
X316800Y211000D03*
X321000D03*
X315900Y216400D03*
X320100D03*
X315900Y220900D03*
X320100D03*
X315900Y234400D03*
X320100D03*
X315900Y229900D03*
X320100D03*
Y225400D03*
X315900D03*
Y247900D03*
X320100D03*
Y238900D03*
X315900D03*
X320100Y243400D03*
X315900D03*
Y252400D03*
X320100D03*
X315900Y256900D03*
X320100D03*
X329600Y216500D03*
X325400D03*
X330700Y388700D03*
X334900D03*
X328700Y413700D03*
X332900D03*
X352200Y383300D03*
X356400D03*
X349400Y378000D03*
X353600D03*
X356400Y403200D03*
X352200D03*
X356400Y398700D03*
X352200D03*
X356400Y407700D03*
X352200D03*
X359400Y419700D03*
X355200D03*
X376900Y97000D03*
X373100Y271000D03*
X368900D03*
X391100Y97000D03*
X386900D03*
X381100D03*
X392600Y268000D03*
X385800D03*
X381600D03*
X385800Y277500D03*
X381600D03*
X392600Y272500D03*
X385800D03*
X381600D03*
X393300Y309200D03*
X389100D03*
X383500D03*
X379300D03*
X383900Y381000D03*
X388100D03*
X383900Y375800D03*
X388100D03*
X410100Y97000D03*
X405900D03*
X396400D03*
X400600D03*
X396800Y268000D03*
Y272500D03*
X401500Y329100D03*
X397300D03*
X401500Y323900D03*
X397300D03*
X414500Y279200D03*
X418700D03*
X432200Y97300D03*
X436400D03*
X446000D03*
X441800D03*
X432450Y112300D03*
X436650D03*
X445850D03*
X441650D03*
X442600Y370000D03*
X438400D03*
X442600Y379000D03*
X438400D03*
X435400Y386500D03*
X439600D03*
X442600Y374500D03*
X438400D03*
X439600Y396500D03*
X435400D03*
X439600Y401500D03*
X435400D03*
Y391500D03*
X439600D03*
X435400Y406500D03*
X439600D03*
X435400Y411500D03*
X439600D03*
X456600Y284500D03*
X452400D03*
X456600Y289500D03*
X452400D03*
X456600Y294500D03*
X452400D03*
Y299500D03*
X456600D03*
X455100Y327000D03*
X450900D03*
X451200Y322000D03*
X455400D03*
X473600Y86500D03*
X469400D03*
X473600Y78500D03*
X469400D03*
X473600Y91500D03*
X469400D03*
X473600Y96500D03*
X469400D03*
X495900Y138500D03*
Y143000D03*
Y133500D03*
X488400Y163000D03*
X492600D03*
X488400Y167500D03*
X492600D03*
X488400Y176500D03*
X492600D03*
Y172000D03*
X488400D03*
Y197500D03*
X492600D03*
X488400Y211500D03*
X492600D03*
X488400Y202500D03*
X492600D03*
X488400Y207000D03*
X492600D03*
X500100Y138500D03*
Y143000D03*
Y133500D03*
X505600Y247400D03*
X501400D03*
X508400Y259700D03*
X504200D03*
X516200Y259200D03*
X508900Y377500D03*
X513100D03*
X524900Y76000D03*
X529100D03*
Y92000D03*
X524900D03*
Y82000D03*
X529100D03*
X524900Y87000D03*
X529100D03*
X520400Y259200D03*
X532000Y395700D03*
X544600Y69000D03*
X540400D03*
X546443Y396700D03*
X550643D03*
X536200Y395700D03*
X564900Y79200D03*
X569100D03*
X556900D03*
X552700D03*
X565400Y240000D03*
X563700Y356900D03*
X559500D03*
X560100Y391500D03*
X555900D03*
Y396000D03*
X560100D03*
X577100Y224500D03*
X572900D03*
X569600Y240000D03*
X576200Y351700D03*
X572000D03*
Y346700D03*
X576200D03*
Y356700D03*
X572000D03*
Y366700D03*
X576200D03*
X572000Y361700D03*
X576200D03*
Y385700D03*
X572000D03*
X576200Y380700D03*
X572000D03*
Y390700D03*
X576200D03*
X572000Y375700D03*
X576200D03*
X595600Y108000D03*
X591400D03*
X595600Y96500D03*
X591400D03*
Y112500D03*
X595600D03*
Y102500D03*
X591400D03*
X602900Y227000D03*
Y222500D03*
X594153Y223900D03*
X589953D03*
Y228402D03*
X594153D03*
X589953Y233000D03*
X594153D03*
X607100Y227000D03*
Y222500D03*
X637900Y96500D03*
Y102000D03*
Y108000D03*
Y113500D03*
X642100Y96500D03*
Y102000D03*
Y108000D03*
Y113500D03*
G54D15*
X29528Y36811D03*
Y373031D03*
X640039Y65354D03*
Y417835D03*
G54D51*
X163222Y391187D03*
Y402013D03*
X336678Y395787D03*
Y406613D03*
G54D33*
X75740Y339350D03*
X72000D03*
X68260D03*
Y350650D03*
X72000D03*
X75740D03*
X373240Y251350D03*
X369500D03*
X365760D03*
Y262650D03*
X369500D03*
X373240D03*
X630729Y220184D03*
X626989D03*
X623249D03*
Y231484D03*
X626989D03*
X630729D03*
G54D60*
X184387Y397600D03*
X207813D03*
G54D127*
G01X83383Y424833D02*
Y429833D01*
X84967D01*
X85473Y429583D01*
X85790Y429250D01*
X85917Y428583D01*
X85790Y427916D01*
X85410Y427500D01*
X84967Y427250D01*
X83383D01*
G01X84967D02*
X85917Y424833D01*
G01X90510D02*
Y429833D01*
X88167Y426250D01*
X91333D01*
G01X94850Y429833D02*
X94343Y429666D01*
X93963Y429250D01*
X93710Y428750D01*
X93520Y428083D01*
X93457Y427333D01*
X93520Y426583D01*
X93710Y425916D01*
X93963Y425416D01*
X94343Y425000D01*
X94850Y424833D01*
X95357Y425000D01*
X95737Y425416D01*
X95990Y425916D01*
X96180Y426583D01*
X96243Y427333D01*
X96180Y428083D01*
X95990Y428750D01*
X95737Y429250D01*
X95357Y429666D01*
X94850Y429833D01*
G01X99950D02*
X99443Y429666D01*
X99063Y429250D01*
X98810Y428750D01*
X98620Y428083D01*
X98557Y427333D01*
X98620Y426583D01*
X98810Y425916D01*
X99063Y425416D01*
X99443Y425000D01*
X99950Y424833D01*
X100457Y425000D01*
X100837Y425416D01*
X101090Y425916D01*
X101280Y426583D01*
X101343Y427333D01*
X101280Y428083D01*
X101090Y428750D01*
X100837Y429250D01*
X100457Y429666D01*
X99950Y429833D01*
G01X103847Y426916D02*
X104290Y427500D01*
X104670Y427833D01*
X105177Y428000D01*
X105620Y427833D01*
X105937Y427500D01*
X106190Y427000D01*
X106253Y426416D01*
X106190Y425916D01*
X105937Y425416D01*
X105557Y425000D01*
X105113Y424833D01*
X104607Y425000D01*
X104163Y425500D01*
X103910Y426250D01*
X103847Y427083D01*
X103973Y428166D01*
X104163Y428750D01*
X104480Y429333D01*
X104923Y429750D01*
X105367Y429833D01*
X105810Y429666D01*
X106127Y429250D01*
G01X109327Y426500D02*
X110973D01*
G01X115757Y427500D02*
X116010Y427750D01*
X116200Y428166D01*
X116327Y428750D01*
X116200Y429250D01*
X115947Y429583D01*
X115503Y429833D01*
X113793D01*
Y424833D01*
X115883D01*
X116327Y425166D01*
X116580Y425666D01*
X116707Y426250D01*
X116580Y426833D01*
X116200Y427333D01*
X115757Y427500D01*
X113793D01*
G01X120350Y429833D02*
X119843Y429666D01*
X119463Y429250D01*
X119210Y428750D01*
X119020Y428083D01*
X118957Y427333D01*
X119020Y426583D01*
X119210Y425916D01*
X119463Y425416D01*
X119843Y425000D01*
X120350Y424833D01*
X120857Y425000D01*
X121237Y425416D01*
X121490Y425916D01*
X121680Y426583D01*
X121743Y427333D01*
X121680Y428083D01*
X121490Y428750D01*
X121237Y429250D01*
X120857Y429666D01*
X120350Y429833D01*
G01X125450D02*
X124943Y429666D01*
X124563Y429250D01*
X124310Y428750D01*
X124120Y428083D01*
X124057Y427333D01*
X124120Y426583D01*
X124310Y425916D01*
X124563Y425416D01*
X124943Y425000D01*
X125450Y424833D01*
X125957Y425000D01*
X126337Y425416D01*
X126590Y425916D01*
X126780Y426583D01*
X126843Y427333D01*
X126780Y428083D01*
X126590Y428750D01*
X126337Y429250D01*
X125957Y429666D01*
X125450Y429833D01*
G01X130550D02*
X130043Y429666D01*
X129663Y429250D01*
X129410Y428750D01*
X129220Y428083D01*
X129157Y427333D01*
X129220Y426583D01*
X129410Y425916D01*
X129663Y425416D01*
X130043Y425000D01*
X130550Y424833D01*
X131057Y425000D01*
X131437Y425416D01*
X131690Y425916D01*
X131880Y426583D01*
X131943Y427333D01*
X131880Y428083D01*
X131690Y428750D01*
X131437Y429250D01*
X131057Y429666D01*
X130550Y429833D01*
G01X135650Y424833D02*
Y429833D01*
X134890Y428833D01*
G01Y424833D02*
X136410D01*
G01X139927Y426500D02*
X141573D01*
G01X145850Y429833D02*
X145343Y429666D01*
X144963Y429250D01*
X144710Y428750D01*
X144520Y428083D01*
X144457Y427333D01*
X144520Y426583D01*
X144710Y425916D01*
X144963Y425416D01*
X145343Y425000D01*
X145850Y424833D01*
X146357Y425000D01*
X146737Y425416D01*
X146990Y425916D01*
X147180Y426583D01*
X147243Y427333D01*
X147180Y428083D01*
X146990Y428750D01*
X146737Y429250D01*
X146357Y429666D01*
X145850Y429833D01*
G01X149747Y429000D02*
X150127Y429500D01*
X150570Y429750D01*
X151077Y429833D01*
X151710Y429666D01*
X152153Y429250D01*
X152280Y428750D01*
X152217Y428250D01*
X151963Y427833D01*
X150697Y427000D01*
X150127Y426416D01*
X149747Y425583D01*
X149620Y424833D01*
X152280D01*
G01X154150Y423166D02*
X157950D01*
G01X159883Y424833D02*
Y429833D01*
X161467D01*
X161973Y429583D01*
X162290Y429250D01*
X162417Y428583D01*
X162290Y427916D01*
X161910Y427500D01*
X161467Y427250D01*
X159883D01*
G01X161467D02*
X162417Y424833D01*
G01X166250Y429833D02*
X165743Y429666D01*
X165363Y429250D01*
X165110Y428750D01*
X164920Y428083D01*
X164857Y427333D01*
X164920Y426583D01*
X165110Y425916D01*
X165363Y425416D01*
X165743Y425000D01*
X166250Y424833D01*
X166757Y425000D01*
X167137Y425416D01*
X167390Y425916D01*
X167580Y426583D01*
X167643Y427333D01*
X167580Y428083D01*
X167390Y428750D01*
X167137Y429250D01*
X166757Y429666D01*
X166250Y429833D01*
G01X171350Y424833D02*
Y429833D01*
X170590Y428833D01*
G01Y424833D02*
X172110D01*
G01X145964Y-110118D02*
G03I-634J0D01*
G01X149695D02*
G03I-1038J0D01*
G01X168013Y-137456D02*
G03I-634J0D01*
G01X155900Y-133655D02*
G03I-632J0D01*
G01X161735Y-128639D02*
G03I-1458J0D01*
G01X158530Y-131428D02*
G03I-1041J0D01*
G01X158461Y-119126D02*
G03I-1283J0D01*
G01X162690Y-117490D02*
G03I-1584J0D01*
G01X169809Y-121292D02*
G03I-2180J0D01*
G01X165531Y-125255D02*
G03I-1869J0D01*
G01X167813Y-115513D02*
G03I-1971J0D01*
G01X154775Y-120500D02*
G03I-892J0D01*
G01X162681Y-102774D02*
G03I-1584J0D01*
G01X158451Y-101149D02*
G03I-1283J0D01*
G01X159258Y-110118D02*
G03I-1868J0D01*
G01X169812Y-98951D02*
G03I-2180J0D01*
G01X167802Y-104739D02*
G03I-1971J0D01*
G01X165183Y-110118D02*
G03I-2180J0D01*
G01X171881D02*
G03I-2642J0D01*
G01X152135Y-98681D02*
G03I-632J0D01*
G01X154064Y-110118D02*
G03I-1460J0D01*
G01X154764Y-99775D02*
G03I-892J0D01*
G01X158530Y-88809D02*
G03I-1041J0D01*
G01X161742Y-91601D02*
G03I-1458J0D01*
G01X165531Y-94981D02*
G03I-1869J0D01*
G01X171080Y-131739D02*
G03I-1282J0D01*
G01X169322Y-135033D02*
G03I-892J0D01*
G01X180669Y-131528D02*
G03I-1870J0D01*
G01X180255Y-136311D02*
G03I-1456J0D01*
G01X179841Y-140261D02*
G03I-1042J0D01*
G01X179433Y-143587D02*
G03I-634J0D01*
G01X181439Y-119680D02*
G03I-2640J0D01*
G01X175373Y-123081D02*
G03I-1968J0D01*
G01X173018Y-127816D02*
G03I-1584J0D01*
G01X174681Y-116876D02*
G03I-2640J0D01*
G01X180979Y-125917D02*
G03I-2180J0D01*
G01X186177Y-123075D02*
G03I-1971J0D01*
G01X188199Y-116876D02*
G03I-2640J0D01*
G01X175452Y-97124D02*
G03I-1968J0D01*
G01X186225Y-97178D02*
G03I-1971J0D01*
G01X181439Y-100556D02*
G03I-2640J0D01*
G01X174681Y-103361D02*
G03I-2640J0D01*
G01X188199D02*
G03I-2640J0D01*
G01X179841Y-79975D02*
G03I-1042J0D01*
G01X171217Y-88444D02*
G03I-1282J0D01*
G01X173123Y-92378D02*
G03I-1584J0D01*
G01X180255Y-83924D02*
G03I-1456J0D01*
G01X180669Y-88708D02*
G03I-1870J0D01*
G01X180979Y-94320D02*
G03I-2180J0D01*
G01X179433Y-76648D02*
G03I-634J0D01*
G01X178347Y429167D02*
X178727Y429667D01*
X179170Y429917D01*
X179677Y430000D01*
X180310Y429833D01*
X180753Y429417D01*
X180880Y428917D01*
X180817Y428417D01*
X180563Y428000D01*
X179297Y427167D01*
X178727Y426583D01*
X178347Y425750D01*
X178220Y425000D01*
X180880D01*
G01X184650Y430000D02*
X184143Y429833D01*
X183763Y429417D01*
X183510Y428917D01*
X183320Y428250D01*
X183257Y427500D01*
X183320Y426750D01*
X183510Y426083D01*
X183763Y425583D01*
X184143Y425167D01*
X184650Y425000D01*
X185157Y425167D01*
X185537Y425583D01*
X185790Y426083D01*
X185980Y426750D01*
X186043Y427500D01*
X185980Y428250D01*
X185790Y428917D01*
X185537Y429417D01*
X185157Y429833D01*
X184650Y430000D01*
G01X188547Y429167D02*
X188927Y429667D01*
X189370Y429917D01*
X189877Y430000D01*
X190510Y429833D01*
X190953Y429417D01*
X191080Y428917D01*
X191017Y428417D01*
X190763Y428000D01*
X189497Y427167D01*
X188927Y426583D01*
X188547Y425750D01*
X188420Y425000D01*
X191080D01*
G01X193647Y429167D02*
X194027Y429667D01*
X194470Y429917D01*
X194977Y430000D01*
X195610Y429833D01*
X196053Y429417D01*
X196180Y428917D01*
X196117Y428417D01*
X195863Y428000D01*
X194597Y427167D01*
X194027Y426583D01*
X193647Y425750D01*
X193520Y425000D01*
X196180D01*
G01X199127Y426667D02*
X200773D01*
G01X205050Y430000D02*
X204543Y429833D01*
X204163Y429417D01*
X203910Y428917D01*
X203720Y428250D01*
X203657Y427500D01*
X203720Y426750D01*
X203910Y426083D01*
X204163Y425583D01*
X204543Y425167D01*
X205050Y425000D01*
X205557Y425167D01*
X205937Y425583D01*
X206190Y426083D01*
X206380Y426750D01*
X206443Y427500D01*
X206380Y428250D01*
X206190Y428917D01*
X205937Y429417D01*
X205557Y429833D01*
X205050Y430000D01*
G01X208947Y429167D02*
X209327Y429667D01*
X209770Y429917D01*
X210277Y430000D01*
X210910Y429833D01*
X211353Y429417D01*
X211480Y428917D01*
X211417Y428417D01*
X211163Y428000D01*
X209897Y427167D01*
X209327Y426583D01*
X208947Y425750D01*
X208820Y425000D01*
X211480D01*
G01X214427Y426667D02*
X216073D01*
G01X219147Y429167D02*
X219527Y429667D01*
X219970Y429917D01*
X220477Y430000D01*
X221110Y429833D01*
X221553Y429417D01*
X221680Y428917D01*
X221617Y428417D01*
X221363Y428000D01*
X220097Y427167D01*
X219527Y426583D01*
X219147Y425750D01*
X219020Y425000D01*
X221680D01*
G01X224057Y425750D02*
X224437Y425333D01*
X224880Y425083D01*
X225450Y425000D01*
X226020Y425167D01*
X226463Y425500D01*
X226780Y426083D01*
X226843Y426750D01*
X226717Y427417D01*
X226400Y427833D01*
X225957Y428167D01*
X225513Y428250D01*
X225070Y428167D01*
X224500Y427833D01*
X224690Y430000D01*
X226400D01*
G01X191096Y-134658D02*
G03I-892J0D01*
G01X192135Y-136781D02*
G03I-631J0D01*
G01X198775Y-128635D02*
G03I-1458J0D01*
G01X195808Y-125255D02*
G03I-1869J0D01*
G01X200547Y-113952D02*
G03X203345Y-117196I7247J3422D01*
G01X192148Y-121285D02*
G03I-2180J0D01*
G01X187928Y-127802D02*
G03I-1584J0D01*
G01X189667Y-131511D02*
G03I-1283J0D01*
G01X200699Y-105836D02*
G03X200547Y-113953I8974J-4228D01*
G01X208284Y-101612D02*
G03X200698Y-105835I-219J-8531D01*
G01X192148Y-98951D02*
G03I-2180J0D01*
G01X191108Y-82727D02*
G03I-634J0D01*
G01X190184Y-85250D02*
G03I-893J0D01*
G01X195808Y-94981D02*
G03I-1869J0D01*
G01X187839Y-92457D02*
G03I-1584J0D01*
G01X189190Y-88538D02*
G03I-1283J0D01*
G01X214259Y-115661D02*
G03X213314Y-114453I-714J415D01*
G01X202049Y-108260D02*
G03X205722Y-116181I7039J-1548D01*
G01X218075Y-112869D02*
G03X219083Y-115752I4343J-99D01*
G01X208854Y-116658D02*
G03X213313Y-114452I-2485J10632D01*
G01X208470Y-118462D02*
G03X214261Y-115663I-1122J9711D01*
G01X203346Y-117195D02*
G03X208470Y-118461I4545J7394D01*
G01X205721Y-116179D02*
G03X208853Y-116659I2561J6250D01*
G01X215903Y-114020D02*
G03X219079Y-118061I6190J1597D01*
G01X215904Y-114020D02*
Y-111835D01*
G01X227413Y-112869D02*
X218074D01*
G01X214175Y-103951D02*
G03X208283Y-101613I-6403J-7542D01*
G01X213150Y-105147D02*
G03X214175Y-103951I410J686D01*
G01X213152Y-105146D02*
G03X208030Y-103430I-5122J-6786D01*
G01X208029Y-103429D02*
G03X202049Y-108259I-48J-6058D01*
G01X225189Y-111399D02*
G03X218071I-3559J159D01*
G01X218070Y-111418D02*
Y-111399D01*
G01X225188Y-111418D02*
X218070D01*
G01X227412Y-111835D02*
G03X215906I-5753J223D01*
G01X230059Y-117625D02*
Y-102034D01*
G01X230060Y-117626D02*
G03X232080I1010J239D01*
G01X226590Y-116472D02*
G03X225311Y-115210I-817J451D01*
G01X234673Y-114020D02*
G03X237849Y-118061I6190J1597D01*
G01X232081Y-102041D02*
Y-117625D01*
G01X219083Y-115753D02*
G03X225311Y-115211I2844J3371D01*
G01X219079Y-118060D02*
G03X226591Y-116473I2662J5972D01*
G01X227413Y-111835D02*
Y-112869D01*
G01X232080Y-102041D02*
G03X230060Y-102034I-1011J-236D01*
G01X225188Y-111399D02*
Y-111418D01*
G01X234675Y-114020D02*
Y-111835D01*
G01X246181D02*
G03X234675I-5753J223D01*
G01X252849Y-116771D02*
G03X254892Y-115895I-74J2994D01*
G01X236844Y-112869D02*
G03X237852Y-115752I4343J-99D01*
G01X237848Y-118060D02*
G03X245360Y-116473I2662J5972D01*
G01X245358Y-116472D02*
G03X244079Y-115210I-817J451D01*
G01X237852Y-115753D02*
G03X244080Y-115211I2844J3371D01*
G01X249566Y-115529D02*
G03X252307Y-116760I2985J2980D01*
G01Y-116761D02*
G03X252849Y-116772I366J4691D01*
G01X250282Y-118087D02*
G03X254318Y-118340I2605J9244D01*
G01X247897Y-116444D02*
G03X250283Y-118086I3752J2898D01*
G01X249568Y-115529D02*
G03X247898Y-116443I-748J-616D01*
G01X255608Y-108618D02*
G03X253612Y-107689I-3116J-4086D01*
G01X246181Y-111835D02*
Y-112869D01*
G01D02*
X236844D01*
G01X255002Y-114328D02*
G03X252723Y-112986I-3540J-3405D01*
G01X249955Y-112030D02*
G03X252723Y-112985I8208J19302D01*
G01X243957Y-111399D02*
Y-111418D01*
G01X243958Y-111399D02*
G03X236840I-3559J159D01*
G01X236841Y-111418D02*
Y-111399D01*
G01X243957Y-111418D02*
X236841D01*
G01X248537Y-109748D02*
G03X249956Y-112031I2652J66D01*
G01X248537Y-108250D02*
Y-109748D01*
G01X250179Y-106359D02*
G03X248537Y-108249I2747J-4045D01*
G01X256884Y-107368D02*
G03X250178Y-106359I-4153J-4811D01*
G01X253611Y-107689D02*
G03X251080Y-107949I-869J-3992D01*
G01X251081Y-107948D02*
G03X250837Y-110104I805J-1183D01*
G01Y-110106D02*
G03X254306Y-111513I5270J8013D01*
G01X260954Y-116041D02*
Y-107954D01*
G01X254892Y-115895D02*
G03X255001Y-114328I-764J840D01*
G01X269619Y-117484D02*
Y-106797D01*
G01X269620Y-117484D02*
G03X271926I1153J198D01*
G01X266864Y-117375D02*
G03X266002Y-116329I-764J249D01*
G01X262978Y-115462D02*
G03X266002Y-116329I2046J1428D01*
G01X260955Y-116043D02*
G03X264164Y-118351I2956J725D01*
G01X265463Y-118350D02*
X264165D01*
G01X265464Y-118352D02*
G03X266864Y-117374I-24J1525D01*
G01X256906Y-116470D02*
G03X257054Y-113728I-3143J1545D01*
G01X254317Y-118340D02*
G03X256906Y-116470I-1259J4470D01*
G01X262978Y-107954D02*
Y-115463D01*
G01X257054Y-113729D02*
G03X254307Y-111513I-3470J-1490D01*
G01X271969Y-102342D02*
G03I-1194J0D01*
G01X271926Y-106797D02*
G03X269620I-1153J-409D01*
G01X266003Y-107954D02*
X262978D01*
G01X266004Y-107955D02*
G03X266008Y-105932I-177J1012D01*
G01X262978D02*
X266008D01*
G01X262971Y-103419D02*
X262978Y-105932D01*
G01X262972Y-103418D02*
G03X260954Y-103491I-1005J-141D01*
G01Y-105932D02*
Y-103492D01*
G01X259930Y-105932D02*
X260954D01*
G01X259930D02*
G03X259981Y-107955I298J-1005D01*
G01X260954Y-107954D02*
X259982D01*
G01X255606Y-108620D02*
G03X256885Y-107367I599J667D01*
G01X290671Y-110842D02*
G03X290703Y-118351I860J-3751D01*
G01X276837Y-114305D02*
G03X278891Y-116297I4069J2141D01*
G01X274529Y-113568D02*
G03X275888Y-116443I5718J944D01*
G01X275887D02*
G03X279572Y-118352I4392J3967D01*
G01X281425Y-118350D02*
X279571D01*
G01X281425D02*
G03X284525Y-117161I0J4636D01*
G01X285201Y-116508D02*
X284524Y-117161D01*
G01X285201Y-116508D02*
G03X283966Y-115211I-695J574D01*
G01X281510Y-116675D02*
G03X283966Y-115212I-989J4453D01*
G01X278889Y-116297D02*
G03X281508Y-116677I1946J4197D01*
G01X271926Y-106797D02*
Y-117484D01*
G01X274529Y-113566D02*
Y-111839D01*
G01X276446Y-112943D02*
G03X276837Y-114305I4162J458D01*
G01X276445Y-112066D02*
Y-112943D01*
G01X283833Y-109274D02*
G03X285403Y-108106I585J852D01*
G01X285402D02*
G03X280919Y-105777I-4776J-3714D01*
G01X279541D02*
X280919D01*
G01X279540D02*
G03X274999Y-109274I1260J-6333D01*
G01X274998D02*
G03X274529Y-111839I9988J-3152D01*
G01X276849Y-109932D02*
G03X276446Y-112066I5467J-2137D01*
G01X280036Y-107542D02*
G03X276849Y-109933I664J-4205D01*
G01X282662Y-108199D02*
G03X280037Y-107539I-2313J-3650D01*
G01X283833Y-109275D02*
G03X282662Y-108202I-9277J-8949D01*
G01X294457Y-116619D02*
G03Y-112289I-51J2165D01*
G01X291853Y-116620D02*
X294456D01*
G01X291853Y-112289D02*
G03Y-116619I195J-2165D01*
G01X294165Y-118350D02*
X290701D01*
G01X294165D02*
G03X296471Y-117226I-1088J5161D01*
G01X296473Y-117625D02*
Y-117226D01*
G01X296474Y-117627D02*
G03X298494I1010J185D01*
G01X298495Y-109394D02*
Y-117625D01*
G01X301067Y-108534D02*
Y-106508D01*
G01X301615Y-108534D02*
X301067D01*
G01X301615Y-106508D02*
Y-108534D01*
G01X302461Y-106508D02*
X301615D01*
G01X302461Y-106001D02*
Y-106508D01*
G01X300223Y-106001D02*
X302461D01*
G01X300223Y-106508D02*
Y-106001D01*
G01X301067Y-106508D02*
X300223D01*
G01X305164Y-106001D02*
X304731D01*
G01X305713Y-108544D02*
X305164Y-106001D01*
G01X305171Y-108544D02*
X305713D01*
G01X304889Y-106871D02*
X305171Y-108544D01*
G01X304309D02*
X304889Y-106871D01*
G01X304086Y-108544D02*
X304309D01*
G01X303501Y-106887D02*
X304086Y-108544D01*
G01X303226D02*
X303501Y-106887D01*
G01X302698Y-108544D02*
X303226D01*
G01X303243Y-106001D02*
X302698Y-108544D01*
G01X303648Y-106001D02*
X303243D01*
G01X304192Y-107632D02*
X303648Y-106001D01*
G01X304731D02*
X304192Y-107632D01*
G01X294456Y-112288D02*
X291853D01*
G01X296473Y-110841D02*
Y-109686D01*
G01X296472Y-110841D02*
G03X292878Y-110536I-3256J-17043D01*
G01X292879Y-110535D02*
G03X290670Y-110842I280J-10112D01*
G01X298496Y-109394D02*
G03X295031Y-105933I-3962J-501D01*
G01X291563Y-105932D02*
X295031D01*
G01X291562D02*
G03X289112Y-107085I584J-4421D01*
G01Y-107086D02*
G03X289820Y-108520I585J-603D01*
G01X290987Y-107954D02*
G03X289821Y-108520I1446J-4464D01*
G01X294740Y-107954D02*
X290987D01*
G01X296473Y-109686D02*
G03X294742Y-107955I-1598J133D01*
G01X383000Y-125000D02*
Y-133000D01*
G01X380700Y-125000D02*
X385300D01*
G01X391000Y-133000D02*
X390200Y-132867D01*
X389500Y-132333D01*
X388900Y-131533D01*
X388500Y-130600D01*
X388300Y-129533D01*
Y-128467D01*
X388500Y-127400D01*
X388900Y-126467D01*
X389500Y-125667D01*
X390200Y-125133D01*
X391000Y-125000D01*
X391800Y-125133D01*
X392500Y-125667D01*
X393100Y-126467D01*
X393500Y-127400D01*
X393700Y-128467D01*
Y-129533D01*
X393500Y-130600D01*
X393100Y-131533D01*
X392500Y-132333D01*
X391800Y-132867D01*
X391000Y-133000D01*
G01X397000D02*
Y-125000D01*
X399400D01*
X400200Y-125400D01*
X400800Y-126333D01*
X401000Y-127400D01*
X400800Y-128467D01*
X400300Y-129267D01*
X399400Y-129667D01*
X397000D01*
G54D43*
X146000Y300700D03*
Y307300D03*
X218600Y403800D03*
Y410400D03*
X223600Y382800D03*
Y389400D03*
X226100Y403800D03*
Y410400D03*
X340000Y371800D03*
Y365200D03*
X332000Y371800D03*
Y365200D03*
X351500Y164800D03*
Y158200D03*
X348000Y371800D03*
Y365200D03*
X370500Y164800D03*
Y158200D03*
X372900Y287000D03*
Y280400D03*
X373200Y295200D03*
Y301800D03*
X445500Y267200D03*
Y273800D03*
X505000Y383700D03*
Y390300D03*
X535000Y178700D03*
Y185300D03*
X525400Y373800D03*
Y367200D03*
X533600Y373800D03*
Y367200D03*
X539000Y159700D03*
Y166300D03*
X538500Y205700D03*
Y212300D03*
X557500Y93200D03*
Y99800D03*
X576000Y208700D03*
Y215300D03*
X622500Y197074D03*
Y203674D03*
G54D61*
X255906Y309646D03*
Y412008D03*
X494094Y309646D03*
Y412008D03*
G54D118*
X651582Y198425D03*
G54D25*
X57100Y389900D03*
Y384500D03*
X145500Y313800D03*
Y319200D03*
X176000Y313300D03*
Y318700D03*
X349100Y250900D03*
Y256300D03*
X493300Y252000D03*
Y246600D03*
X512000Y390700D03*
Y385300D03*
X539500Y222900D03*
Y228300D03*
X570000Y93300D03*
Y98700D03*
G54D52*
X158104Y391187D03*
Y402013D03*
X341796Y395787D03*
Y406613D03*
G54D109*
X553600Y364025D03*
G54D70*
X350595Y189187D03*
X358207Y192336D03*
Y193911D03*
Y189187D03*
Y190762D03*
X350595Y193911D03*
Y190762D03*
Y192336D03*
G54D16*
X19878Y36811D03*
X22704Y29987D03*
Y43635D03*
X22834Y340080D03*
X26378D03*
X28150Y343150D03*
X24606D03*
X19878Y373031D03*
X22704Y366207D03*
Y379855D03*
X29528Y27161D03*
X36352Y29987D03*
X39178Y36811D03*
X36352Y43635D03*
X29528Y46461D03*
X29922Y340080D03*
X33466D03*
X37010D03*
X40554D03*
X44098D03*
X45870Y343150D03*
X42326D03*
X38782D03*
X35238D03*
X31694D03*
X29528Y363381D03*
X36352Y366207D03*
X39178Y373031D03*
X36352Y379855D03*
X29528Y382681D03*
X633215Y58530D03*
Y72178D03*
X630389Y65354D03*
X633215Y424659D03*
X630389Y417835D03*
X633215Y411011D03*
X640039Y55704D03*
X646863Y58530D03*
X649689Y65354D03*
X646863Y72178D03*
X640039Y75004D03*
Y408185D03*
X646863Y411011D03*
X649689Y417835D03*
X646863Y424659D03*
X640039Y427485D03*
G54D34*
X69300Y373600D03*
X87300D03*
G54D128*
G01X147143Y403100D02*
X148300D01*
X152100Y399300D01*
G01X160860Y390104D02*
Y389660D01*
X158600Y387400D01*
X157900D01*
G01X152100Y399300D02*
X153816Y397584D01*
X158104D01*
G01X351200Y196600D02*
X350595Y195995D01*
Y193911D01*
G01X349128Y186628D02*
X348501Y187255D01*
Y188387D01*
X349301Y189187D01*
X350595D01*
G01X548557Y391200D02*
Y387700D01*
G01X551631Y383456D02*
Y390212D01*
X550643Y391200D01*
G01D02*
Y396700D01*
G01D02*
Y400900D01*
G01D02*
X545399D01*
X544099Y399600D01*
X540100D01*
X536200Y395700D01*
G01X572000Y366700D02*
X568400D01*
X568100Y366400D01*
G01D02*
X566600D01*
X563237Y369763D01*
X559271D01*
G01X568100Y361700D02*
X562006Y367794D01*
X559271D01*
G01X568326Y371200D02*
X567031D01*
X566500Y371731D01*
X559271D01*
G01X564500Y379000D02*
X563137Y377637D01*
X559271D01*
G01X572000Y385700D02*
X571200Y386500D01*
X567500D01*
G01D02*
Y385100D01*
X562006Y379606D01*
X559271D01*
G01X568600Y376000D02*
X566300Y373700D01*
X559271D01*
G01X568600Y380700D02*
Y380200D01*
X564069Y375669D01*
X559271D01*
G01X573143Y371200D02*
X576300D01*
G01X572000Y361700D02*
X568100D01*
G01X571057Y371200D02*
X568326D01*
G01X572000Y375700D02*
X571700Y376000D01*
X568600D01*
G01X572000Y380700D02*
X568600D01*
G54D80*
X391200Y294500D03*
G54D35*
X78300Y401800D03*
G54D62*
X275400Y57941D03*
X284800D03*
Y63059D03*
X275400D03*
Y60500D03*
G54D26*
X73662Y70850D03*
X76221D03*
X78780D03*
X73662Y94750D03*
X76221D03*
X78780D03*
X81339Y70850D03*
Y94750D03*
G54D44*
X166220Y59000D03*
Y64000D03*
Y69000D03*
Y74000D03*
X188320Y59000D03*
Y64000D03*
Y69000D03*
Y74000D03*
G54D53*
X165781Y391187D03*
Y402013D03*
X170112Y391187D03*
X167946D03*
Y402013D03*
X170112D03*
X334119Y395787D03*
X331954D03*
X329788D03*
Y406613D03*
X331954D03*
X334119D03*
G54D17*
X16039Y71260D03*
Y128346D03*
Y185433D03*
Y242520D03*
G54D119*
X640952Y201181D03*
Y220867D03*
G54D71*
X355189Y188543D03*
X353614D03*
X355189Y194555D03*
X353614D03*
G54D129*
G01X12500Y91000D02*
X12000D01*
X11367Y91633D01*
X6874D01*
G01X12500Y101000D02*
Y100826D01*
X10197Y98523D01*
X8252D01*
G01X12500Y106000D02*
X10807D01*
X6874Y102067D01*
G01Y148720D02*
X13620D01*
G01X8252Y155610D02*
X11610D01*
X13000Y157000D01*
G01X12500Y162000D02*
X9654Y159154D01*
X6874D01*
G01X12500Y204500D02*
X11193Y205807D01*
X6874D01*
G01X12500Y214500D02*
X12000D01*
X10197Y212697D01*
X8252D01*
G01X12500Y219500D02*
X9241Y216241D01*
X6874D01*
G01X12500Y261500D02*
X11000D01*
X9607Y262893D01*
X6874D01*
G01X28700Y274300D02*
X28000Y275000D01*
X18400D01*
X13183Y269783D01*
X8252D01*
G01X6874Y273327D02*
X13000D01*
G01X6874Y319980D02*
X9720D01*
X11000Y318700D01*
X13000D01*
G01X28000Y327000D02*
X15000D01*
X14870Y326870D01*
X8252D01*
G01X6874Y330414D02*
X32086D01*
X35500Y327000D01*
G01X16039Y71260D02*
Y82039D01*
X27250Y93250D01*
Y95650D01*
G01X16039Y128346D02*
Y116961D01*
X27250Y105750D01*
Y104350D01*
G01X45500Y104390D02*
X45460Y104350D01*
X27250D01*
G01X44500Y73500D02*
X40000Y78000D01*
Y86000D01*
X30350Y95650D01*
X27250D01*
G01X19100Y152698D02*
Y148798D01*
G01X23600Y152698D02*
Y148798D01*
G01X19100Y156898D02*
X23600D01*
G01X13620Y148720D02*
X13903Y149003D01*
Y154137D01*
X16664Y156898D01*
X19100D01*
G01X13000Y157000D02*
X16500Y160500D01*
X24498D01*
X28100Y156898D01*
G01X37100D02*
X31998Y162000D01*
X12500D01*
G01X16039Y185433D02*
Y197539D01*
X27250Y208750D01*
Y209650D01*
G01X45500Y182500D02*
X35500Y192500D01*
Y207500D01*
X33350Y209650D01*
X27250D01*
G01X16039Y242520D02*
Y230461D01*
X27250Y219250D01*
Y218350D01*
G01D02*
X44850D01*
X46000Y219500D01*
G01X19000Y262500D02*
X19700Y263200D01*
Y266408D01*
G01X24200D02*
Y262508D01*
G01X19700Y270608D02*
X17608D01*
X15700Y268700D01*
Y263700D01*
X13500Y261500D01*
X12500D01*
G01X19700Y270608D02*
X24200D01*
G01X13000Y273327D02*
X16673Y277000D01*
X31308D01*
X37700Y270608D01*
G01X18000Y318900D02*
Y314500D01*
G01X44500Y309000D02*
X42265Y306765D01*
X32235D01*
X23000Y316000D01*
Y318900D01*
G01X13000Y318700D02*
X15100Y320800D01*
Y322630D01*
X15570Y323100D01*
X18000D01*
G01D02*
X23000D01*
G01X44300Y64700D02*
Y63100D01*
X47172Y60228D01*
X50500D01*
G01X46000Y82000D02*
Y84300D01*
X44700Y85600D01*
Y91401D01*
X45899Y92600D01*
X48500D01*
G01X48390Y128312D02*
X48312D01*
X48000Y128000D01*
X47500D01*
X43644Y131856D01*
Y147144D01*
X45100Y148600D01*
X48000D01*
G01X41600Y152698D02*
Y148798D01*
G01X32600Y152698D02*
Y148700D01*
G01X37100Y152698D02*
Y148798D01*
G01X28100Y152698D02*
Y148798D01*
G01Y156898D02*
X32600D01*
G01X37100D02*
X41600D01*
G01X40500Y262000D02*
X37700Y264800D01*
Y266408D01*
G01X33200D02*
Y262508D01*
G01X52500Y278000D02*
X50500D01*
X45000Y272500D01*
Y263900D01*
X47800Y261100D01*
G01X43000Y255500D02*
Y264000D01*
X42200Y264800D01*
Y266408D01*
G01X28700D02*
Y262508D01*
G01Y270608D02*
X33200D01*
G01X28700D02*
Y274300D01*
G01X37700Y270608D02*
X42200D01*
G01X43000Y318900D02*
Y314500D01*
G01X33000Y318900D02*
Y314500D01*
G01X39500Y309000D02*
Y311499D01*
X38000Y312999D01*
Y318900D01*
G01X28000D02*
Y315500D01*
X34500Y309000D01*
G01X33000Y323100D02*
X28000D01*
G01D02*
Y327000D01*
G01X43000Y323100D02*
X38000D01*
G01X35500Y327000D02*
X38000Y324500D01*
Y323100D01*
G01X37010Y340080D02*
Y337490D01*
X38500Y336000D01*
X55000D01*
G01X55500Y59000D02*
Y60000D01*
X55708Y60208D01*
Y64606D01*
G01X53740D02*
Y68260D01*
X53395Y68605D01*
X52105D01*
X51772Y68272D01*
Y64606D01*
G01X50500Y60228D02*
X51772Y61500D01*
Y64606D01*
G01X55708Y77914D02*
Y82208D01*
X57000Y83500D01*
G01D02*
X53500Y87000D01*
Y88400D01*
G01X63500Y84500D02*
Y87000D01*
X62100Y88400D01*
X58000D01*
G01D02*
Y86500D01*
X59500Y85000D01*
Y82000D01*
X57676Y80176D01*
Y77914D01*
G01X53500Y92600D02*
Y94865D01*
X51765Y96600D01*
G01X53740Y77914D02*
Y81260D01*
X51500Y83500D01*
G01D02*
X48500Y86500D01*
Y88400D01*
G01X45500Y108390D02*
Y104390D01*
G01X57500Y101500D02*
X56000Y100000D01*
X52443D01*
G01X50500Y112590D02*
X56090D01*
X56500Y113000D01*
G01X50500Y112590D02*
Y115000D01*
X51500Y116000D01*
X53208D01*
X55708Y118500D01*
Y121692D01*
G01X45500Y117800D02*
X51100D01*
X51772Y118472D01*
Y121692D01*
G01X45500Y117800D02*
Y112590D01*
G01X51772Y121692D02*
Y125530D01*
X52242Y126000D01*
X53740D01*
G01D02*
Y121692D01*
G01X55922Y140543D02*
Y140422D01*
X55708Y140208D01*
Y135000D01*
G01X53000Y144400D02*
X55922Y141478D01*
Y140543D01*
G01X57676Y135000D02*
X59000D01*
X64500Y129500D01*
G01X58000Y144400D02*
Y142000D01*
X58500Y141500D01*
Y138500D01*
X57676Y137676D01*
Y135000D01*
G01X47500Y140500D02*
Y143900D01*
X48000Y144400D01*
G01X47500Y140500D02*
X50939D01*
X53740Y137699D01*
Y135000D01*
G01X54130Y152500D02*
X53000Y151370D01*
Y148600D01*
G01X60600Y157000D02*
X66356Y162756D01*
X70500D01*
G01X48957Y153619D02*
Y157000D01*
G01X55708Y178779D02*
Y172208D01*
X54500Y171000D01*
G01X55600Y165000D02*
Y169900D01*
X54500Y171000D01*
G01X51772Y178779D02*
Y175472D01*
X50200Y173900D01*
X45500D01*
G01D02*
Y168600D01*
G01X53500Y183500D02*
X52500D01*
X51772Y182772D01*
Y178779D01*
G01X53500Y183500D02*
X53740Y183260D01*
Y178779D01*
G01X45500Y178100D02*
Y182500D01*
G01X62000Y199500D02*
X57676Y195176D01*
Y192087D01*
G01X53740D02*
Y195560D01*
X48800Y200500D01*
X48000D01*
G01X55708Y192087D02*
Y197792D01*
X53000Y200500D01*
G01X57500Y204900D02*
X62017Y200383D01*
Y199517D01*
X62000Y199500D01*
G01X45000Y213000D02*
X46255D01*
X48000Y211255D01*
Y209100D01*
G01X54000Y213500D02*
X53800D01*
X53000Y212700D01*
Y209100D01*
G01X48000Y200500D02*
Y204900D01*
G01X53000Y200500D02*
Y204900D01*
G01X49600Y213455D02*
Y216557D01*
X49557Y216600D01*
G01X51452Y227500D02*
X53000D01*
X54000Y226500D01*
X57500D01*
G01D02*
Y229500D01*
X55708Y231292D01*
Y235866D01*
G01X51772D02*
Y233372D01*
X51000Y232600D01*
X45200D01*
G01D02*
Y228752D01*
X46452Y227500D01*
G01X46000Y219500D02*
X46452Y219952D01*
Y223300D01*
G01X57676Y249174D02*
Y256776D01*
X57800Y256900D01*
G01X53740Y249174D02*
Y251530D01*
X53270Y252000D01*
X49000D01*
X48500Y252500D01*
G01X53740Y235866D02*
Y239647D01*
X53200Y240187D01*
G01D02*
X52200D01*
X51772Y239759D01*
Y235866D01*
G01X55200Y253500D02*
Y253038D01*
X55708Y252530D01*
Y249174D01*
G01X57800Y256900D02*
X59500D01*
X64700Y251700D01*
G01X48232Y264530D02*
X48262Y264500D01*
X49400D01*
X51300Y262600D01*
X53000D01*
G01X48500Y252500D02*
X47800Y253200D01*
Y256900D01*
G01X53000Y258400D02*
Y255700D01*
X55200Y253500D01*
G01X52800Y272000D02*
X51743Y270943D01*
Y268000D01*
G01X62000Y323500D02*
X62501D01*
X64736Y325735D01*
X65735D01*
X67265Y327265D01*
X72341D01*
X74235Y329159D01*
Y332748D01*
X77487Y336000D01*
X82661D01*
X84514Y337853D01*
X89400D01*
G01X55000Y336000D02*
Y332900D01*
X58900Y329000D01*
G01X59500Y355400D02*
X55000D01*
G01X76321Y78300D02*
X76090Y78531D01*
Y83530D01*
X75570Y84050D01*
X73120D01*
X71860Y82790D01*
Y80240D01*
X73920Y78180D01*
Y77110D01*
X76221Y74809D01*
Y70850D01*
G01X71500Y77000D02*
X73662Y74838D01*
Y70850D01*
G01X78780D02*
Y65280D01*
X75500Y62000D01*
G01X77900Y110000D02*
Y105000D01*
G01X67500Y114500D02*
X72000Y110000D01*
X77900D01*
G01X79000Y100500D02*
X78800Y100300D01*
Y100000D01*
X78780Y99980D01*
Y94750D01*
G01X74000Y100500D02*
X75600D01*
X76221Y99879D01*
Y94750D01*
G01X77900Y120000D02*
Y115000D01*
G01X68000Y119000D02*
X68500D01*
X72500Y115000D01*
X77900D01*
G01Y125000D02*
Y130000D01*
G01X73500Y119000D02*
Y120600D01*
X77900Y125000D01*
G01X69500Y130000D02*
X70500Y131000D01*
Y142244D01*
G01X74000Y130000D02*
Y131500D01*
X76000Y133500D01*
X80000D01*
X80500Y134000D01*
Y142244D01*
G01X78747Y175000D02*
X80500D01*
X83500Y178000D01*
G01X90500Y188500D02*
X81500Y179500D01*
X78747D01*
G01X74547D02*
Y175000D01*
G01Y179500D02*
X73500D01*
X69000Y184000D01*
Y187500D01*
G01X78747Y193000D02*
X83500D01*
G01X78747Y188500D02*
X83500D01*
G01X94500Y197000D02*
X94000Y197500D01*
X78747D01*
G01X90500Y193500D02*
X85735Y188735D01*
Y186705D01*
X83030Y184000D01*
X78747D01*
G01X74547Y188500D02*
Y184000D01*
G01X69000Y193000D02*
Y192500D01*
X73000Y188500D01*
X74547D01*
G01Y197500D02*
Y193000D01*
G01Y197500D02*
X70047D01*
X69023Y198524D01*
G01X79500Y234500D02*
Y229500D01*
X80820Y228180D01*
Y224650D01*
G01X79600Y248900D02*
X80820Y247680D01*
Y242750D01*
G01X68448Y266400D02*
X70600D01*
X72400Y264600D01*
G01D02*
X73100D01*
X74600Y266100D01*
X75897D01*
G01X72000Y271400D02*
Y271000D01*
X72500Y270500D01*
X74899D01*
X75897Y269502D01*
Y268069D01*
G01Y264131D02*
X74066Y262300D01*
X69348D01*
X68448Y261400D01*
G01D02*
Y258852D01*
X69500Y257800D01*
G01X76948Y256700D02*
X77964Y257716D01*
Y260100D01*
G01D02*
Y263049D01*
G01X64248Y266400D02*
Y270900D01*
G01X75800Y274300D02*
Y273400D01*
X77964Y271236D01*
Y269151D01*
G01X71400Y279000D02*
Y277100D01*
X74200Y274300D01*
X75800D01*
G01X72000Y271400D02*
Y274000D01*
X69074Y276926D01*
X68174D01*
X66100Y279000D01*
G01X80648Y283100D02*
X76100D01*
X75500Y282500D01*
G01X75600Y279000D02*
Y282400D01*
X75500Y282500D01*
G01X64248Y270900D02*
Y273552D01*
X63800Y274000D01*
G01X70400Y320000D02*
Y317854D01*
X69929Y317383D01*
X67117D01*
X66000Y318500D01*
G01X79000Y315500D02*
X83000Y319500D01*
Y324500D01*
X86510Y328010D01*
X89400D01*
G01X74600Y320000D02*
X80800D01*
X81270Y320470D01*
Y326259D01*
X82951Y327940D01*
G01X79500Y308500D02*
X84500Y313500D01*
Y324000D01*
X86542Y326042D01*
X89400D01*
G01X70400Y324500D02*
X69400Y323500D01*
X66000D01*
G01X74600Y324500D02*
X78627D01*
X78635Y324492D01*
G01X89400Y331947D02*
X81470D01*
X81000Y331477D01*
Y329501D01*
X78635Y327136D01*
Y324492D01*
G01X78000Y330500D02*
Y332000D01*
X80000Y334000D01*
X83616D01*
X85500Y335884D01*
X89400D01*
G01Y341790D02*
X79500D01*
G01Y348500D02*
X80305Y347695D01*
X89400D01*
G01X95750Y65360D02*
X100460D01*
X103600Y68500D01*
X110900D01*
X112800Y66600D01*
G01X117370Y70860D02*
X114734D01*
X114274Y70400D01*
X103700D01*
X101260Y72840D01*
X95750D01*
G01X96500Y98000D02*
X99000Y100500D01*
Y153500D01*
X95500Y157000D01*
Y160839D01*
X96735Y162074D01*
Y163926D01*
X95000Y165661D01*
Y177500D01*
X91000Y181500D01*
G01X88250Y177250D02*
Y167750D01*
X91000Y165000D01*
Y148000D01*
X93265Y145735D01*
Y144574D01*
X94000Y143839D01*
Y134500D01*
X97000Y131500D01*
Y102000D01*
X92750Y97750D01*
X92250D01*
G01X89000Y110500D02*
X88000D01*
X82500Y105000D01*
X82100D01*
G01X93500Y125000D02*
Y119500D01*
X84000Y110000D01*
X82100D01*
G01X84000Y100500D02*
X82500D01*
X81339Y99339D01*
Y94750D01*
G01X82100Y120000D02*
X87000D01*
G01X82100Y125000D02*
X86500D01*
X87000Y125500D01*
G01X93500Y130000D02*
X91000Y127500D01*
Y120500D01*
X85500Y115000D01*
X82100D01*
G01Y130000D02*
X87000D01*
G01X83500Y173000D02*
Y170000D01*
X80500Y167000D01*
Y162756D01*
G01X84500Y218000D02*
X83296D01*
X80400Y215104D01*
G01X82500Y230500D02*
X83380Y229620D01*
Y224650D01*
G01X84600Y248900D02*
X83380Y247680D01*
Y242750D01*
G01X89600Y248900D02*
X85940Y245240D01*
Y242750D01*
G01X83200Y260300D02*
X82531D01*
X79932Y262899D01*
Y263049D01*
G01X83500Y256600D02*
Y260000D01*
X83200Y260300D01*
G01X82500Y273200D02*
X82000D01*
X79932Y271132D01*
Y269151D01*
G01X87500Y295500D02*
Y297500D01*
X92000Y302000D01*
Y314500D01*
X97500Y320000D01*
Y323000D01*
X96427Y324073D01*
X89400D01*
G01Y320136D02*
Y303900D01*
X88500Y303000D01*
G01X97536Y312000D02*
Y302036D01*
X94500Y299000D01*
G01X99505Y312000D02*
Y296005D01*
X95000Y291500D01*
G01X89400Y329979D02*
X84990D01*
X82951Y327940D01*
G01X89400Y339821D02*
X83321D01*
X82500Y339000D01*
G01X95100Y351900D02*
X96200D01*
X97536Y353236D01*
Y357800D01*
G01X83000Y352500D02*
Y352000D01*
X83500Y351500D01*
X83900D01*
X85736Y349664D01*
X89400D01*
G01X83000Y344500D02*
Y345000D01*
X83727Y345727D01*
X89400D01*
G01X112800Y66600D02*
X113600Y65800D01*
X117310D01*
X117370Y65860D01*
G01X107050Y72840D02*
X112700D01*
X112880Y73020D01*
G01D02*
X115220Y75360D01*
X117370D01*
G01X117500Y298100D02*
X112500D01*
G01X109347Y312000D02*
Y307653D01*
X112500Y304500D01*
Y302000D01*
G01D02*
Y298100D01*
G01X107500D02*
Y302000D01*
G01D02*
Y306000D01*
X107379Y306121D01*
Y312000D01*
G01X112500Y293900D02*
Y290000D01*
G01X102500Y293900D02*
X107500D01*
G01X102500D02*
Y290000D01*
G01X103000Y351500D02*
X101473Y353027D01*
Y357800D01*
G01X105500Y368900D02*
X102836D01*
X101736Y370000D01*
X99500D01*
G01X105500Y373100D02*
X104500Y374100D01*
Y377000D01*
G01X126000Y67000D02*
X127070D01*
X130870Y70800D01*
G01Y75300D02*
Y70800D01*
G01X126000Y67000D02*
X124600Y68400D01*
X117840D01*
X117370Y68870D01*
Y70860D01*
G01X130850Y61300D02*
Y65800D01*
G01Y61300D02*
X127100D01*
X126400Y62000D01*
X126000D01*
G01D02*
X122140Y65860D01*
X121570D01*
G01X126000Y318000D02*
X127064Y316936D01*
Y312000D01*
G01X129500Y328000D02*
X131458Y326042D01*
X135200D01*
G01X119000Y352000D02*
X117221Y353779D01*
Y357800D01*
G01X123127D02*
Y374773D01*
X122900Y375000D01*
G01X127100D02*
Y374100D01*
X125095Y372095D01*
Y357800D01*
G01X123543Y379000D02*
Y375643D01*
X122900Y375000D01*
G01X123543Y379000D02*
Y382780D01*
X121169Y385154D01*
G01X127100Y375000D02*
Y378857D01*
X126957Y379000D01*
G01D02*
X125500Y380457D01*
Y387999D01*
X129347Y391846D01*
X129831D01*
G01X139500Y62500D02*
X142100Y59900D01*
X142930D01*
X143400Y59430D01*
Y57370D01*
X142930Y56900D01*
X136200D01*
X135050Y58050D01*
Y61300D01*
G01X148500Y62500D02*
X145000Y66000D01*
Y70500D01*
X143500Y72000D01*
X139500D01*
X138300Y70800D01*
X135070D01*
G01X145900Y75200D02*
X148500Y77800D01*
X170240D01*
X177240Y70800D01*
Y67060D01*
X180910Y63390D01*
G01X151200Y75191D02*
X156519D01*
X157300Y74410D01*
Y73000D01*
X156830Y72530D01*
X147640D01*
X147170Y72060D01*
Y70530D01*
X147640Y70060D01*
X158100D01*
X159160Y69000D01*
Y64470D01*
X159630Y64000D01*
X166220D01*
G01X142070Y77900D02*
X137670D01*
X135070Y75300D01*
G01X142000Y69535D02*
X138265Y65800D01*
X135050D01*
G01X205000Y348800D02*
X198530D01*
X198060Y349270D01*
Y351430D01*
X197590Y351900D01*
X196060D01*
X195590Y351430D01*
Y349270D01*
X195120Y348800D01*
X193590D01*
X193120Y349270D01*
Y351430D01*
X192650Y351900D01*
X191120D01*
X190650Y351430D01*
Y349270D01*
X190180Y348800D01*
X188650D01*
X188180Y349270D01*
Y351430D01*
X187710Y351900D01*
X186180D01*
X185710Y351430D01*
Y349270D01*
X185240Y348800D01*
X183710D01*
X183240Y349270D01*
Y351430D01*
X182770Y351900D01*
X181240D01*
X180770Y351430D01*
Y349270D01*
X180300Y348800D01*
X178770D01*
X178300Y349270D01*
Y351430D01*
X177830Y351900D01*
X176300D01*
X175830Y351430D01*
Y349270D01*
X175360Y348800D01*
X164300D01*
X161227Y345727D01*
X135200D01*
G01X205000Y353800D02*
X199960D01*
X199490Y354270D01*
Y356330D01*
X199020Y356800D01*
X197490D01*
X197020Y356330D01*
Y354270D01*
X196550Y353800D01*
X195020D01*
X194550Y354270D01*
Y356330D01*
X194080Y356800D01*
X192550D01*
X192080Y356330D01*
Y354270D01*
X191610Y353800D01*
X190080D01*
X189610Y354270D01*
Y356330D01*
X189140Y356800D01*
X187610D01*
X187140Y356330D01*
Y354270D01*
X186670Y353800D01*
X185140D01*
X184670Y354270D01*
Y356330D01*
X184200Y356800D01*
X182670D01*
X182200Y356330D01*
Y354270D01*
X181730Y353800D01*
X180200D01*
X179730Y354270D01*
Y356330D01*
X179260Y356800D01*
X177730D01*
X177260Y356330D01*
Y354270D01*
X176790Y353800D01*
X166800D01*
X160695Y347695D01*
X135200D01*
G01X215000Y343800D02*
X205000D01*
X202300Y346500D01*
X164500D01*
X161758Y343758D01*
X135200D01*
G01X138250Y372250D02*
Y380850D01*
X142500Y385100D01*
G01X147143Y390100D02*
Y387979D01*
X146700Y387536D01*
Y385100D01*
G01X151117Y386283D02*
X149934Y385100D01*
X146700D01*
G01X153500Y390500D02*
X151800D01*
X147700Y394600D01*
G01X173170Y70840D02*
X171330Y69000D01*
X166220D01*
G01X152600Y295000D02*
X153000Y295400D01*
Y300400D01*
G01X162033Y301500D02*
X157200D01*
X156800Y301100D01*
G01D02*
X156100Y300400D01*
X153000D01*
G01X162033Y299531D02*
X158531D01*
X156600Y297600D01*
Y295000D01*
G01X158104Y391187D02*
X154917Y388000D01*
X153800D01*
X152083Y386283D01*
X151117D01*
G01D02*
X151100Y386300D01*
G01X158104Y393647D02*
X156647D01*
X153500Y390500D01*
G01X180390Y70720D02*
X182110Y69000D01*
X188320D01*
G01X180910Y63390D02*
X181520Y64000D01*
X188320D01*
G01X188500Y293900D02*
X183500D01*
G01X173967Y299531D02*
X177969D01*
X179500Y298000D01*
Y294600D01*
G01D02*
X180200Y293900D01*
X183500D01*
G01X191535Y41200D02*
Y41064D01*
X195472Y37127D01*
Y13781D01*
G01X199409D02*
Y35226D01*
X198135Y36500D01*
G01X199770Y59000D02*
X204770D01*
G01X188320D02*
X192890D01*
X195000Y56890D01*
Y54550D01*
G01D02*
X197467D01*
X199770Y56853D01*
Y59000D01*
G01X196497Y76502D02*
Y66473D01*
X199770Y63200D01*
G01X201700Y327900D02*
Y330200D01*
X206500Y335000D01*
X210500D01*
X212220Y333280D01*
Y326550D01*
G01X195900Y324700D02*
X198500D01*
X201700Y327900D01*
G01X217300Y297300D02*
Y300500D01*
X218500Y301700D01*
G01X214780Y308450D02*
Y304820D01*
X216300Y303300D01*
X216900D01*
X218500Y301700D01*
G01X212220Y308450D02*
Y304280D01*
X213500Y303000D01*
Y301700D01*
G01D02*
X212800Y301000D01*
Y297300D01*
G01X209660Y308450D02*
Y302860D01*
X208500Y301700D01*
G01D02*
X208300Y301500D01*
Y297300D01*
G01X226500Y334000D02*
X217500D01*
X214780Y331280D01*
Y326550D01*
G01X217340D02*
Y330340D01*
X218000Y331000D01*
X221000D01*
X222000Y330000D01*
G01X226500Y334000D02*
X271000D01*
X282000Y345000D01*
X316000D01*
X319500Y341500D01*
Y337499D01*
X324219Y332780D01*
X328150D01*
G01X222500Y324500D02*
X226280D01*
G01D02*
X242350D01*
X250025Y332175D01*
X271775D01*
X282100Y342500D01*
X315500D01*
X318000Y340000D01*
Y336500D01*
X324280Y330220D01*
X328150D01*
G01X222000Y330000D02*
X224100D01*
X225400Y328700D01*
X226280D01*
G01X250590Y13781D02*
Y29963D01*
X254527Y33900D01*
G01X243500Y48650D02*
Y59200D01*
X246900Y62600D01*
X251122D01*
G01X252700Y44000D02*
Y56822D01*
X251122Y58400D01*
G01X275400Y60500D02*
X272170D01*
X268800Y57130D01*
Y54700D01*
X266300Y52200D01*
X263300D01*
G01D02*
Y57900D01*
X263700Y58300D01*
Y60500D01*
G01D02*
Y65500D01*
G01X284800Y57941D02*
X294900D01*
X295400Y57441D01*
G01X332500Y306500D02*
X326500Y312500D01*
X305000D01*
X299000Y306500D01*
X291000D01*
X283500Y314000D01*
Y337000D01*
X284398Y337898D01*
X304250D01*
G01X328000Y306500D02*
X324000Y310500D01*
X307000D01*
X300500Y304000D01*
X290671D01*
X281500Y313171D01*
Y339000D01*
X282957Y340457D01*
X304250D01*
G01X307300Y61300D02*
Y55800D01*
X305000Y53500D01*
Y27500D01*
X305708Y26792D01*
Y15731D01*
G01X503005Y99494D02*
X500000Y96489D01*
Y72501D01*
X494999Y67500D01*
X472500D01*
X470500Y65500D01*
X363000D01*
X357000Y71500D01*
X312753D01*
X304200Y62947D01*
Y57694D01*
X301512Y55006D01*
X295494D01*
X295400Y55100D01*
Y57441D01*
G01X299700Y62100D02*
Y57541D01*
X299600Y57441D01*
G01X312500Y160500D02*
X320500Y152500D01*
Y121000D01*
X323000Y118500D01*
Y85500D01*
X299700Y62200D01*
Y62100D01*
G01X298284Y175184D02*
X292734D01*
G01X357000Y295500D02*
X354500Y298000D01*
X338500D01*
X335500Y301000D01*
Y307000D01*
X327500Y315000D01*
X319500D01*
X313100Y321400D01*
Y331500D01*
X311820Y332780D01*
X304250D01*
G01X356000Y302300D02*
X354200Y300500D01*
X338500D01*
X337500Y301500D01*
Y307500D01*
X331585Y313415D01*
Y314079D01*
X332920Y315414D01*
Y316078D01*
X331837Y317161D01*
X331173D01*
X329838Y315826D01*
X329174D01*
X328250Y316750D01*
X320750D01*
X315500Y322000D01*
Y333499D01*
X311999Y337000D01*
X309300D01*
X307639Y335339D01*
X304250D01*
G01X297700Y335100D02*
Y331900D01*
X299380Y330220D01*
X304250D01*
G01X298700Y327000D02*
X299361Y327661D01*
X304250D01*
G01X298700Y327000D02*
X298300D01*
X295300Y330000D01*
Y331700D01*
X293800Y333200D01*
G01X298700Y323500D02*
X300302Y325102D01*
X304250D01*
G01X293700Y325900D02*
X296300D01*
X298700Y323500D01*
G01X289600Y330100D02*
Y333200D01*
G01X293200Y329500D02*
X292100D01*
X289500Y326900D01*
Y325900D01*
G01X306500Y169500D02*
X312400D01*
G01X316600D02*
Y164500D01*
G01X320500Y170000D02*
X320000Y169500D01*
X316600D01*
G01X329600Y216500D02*
Y216352D01*
X327248Y214000D01*
X322500D01*
X320100Y216400D01*
G01Y225400D02*
X322200Y227500D01*
X324000D01*
G01X320100Y229900D02*
Y234400D01*
G01X327500Y232000D02*
X322500D01*
X320400Y229900D01*
X320100D01*
G01X315900Y220900D02*
Y225400D01*
G01D02*
X312500D01*
G01X315900Y229900D02*
X311900D01*
G01X320100Y238900D02*
Y234400D01*
G01X328500Y238645D02*
X328155D01*
X323000Y243800D01*
Y249500D01*
X320100Y252400D01*
G01Y247900D02*
Y243400D01*
G01X324000Y236000D02*
Y239500D01*
X320100Y243400D01*
G01Y256900D02*
X322100D01*
X324300Y254700D01*
G01X458500Y86500D02*
Y84500D01*
X462500Y80500D01*
Y71500D01*
X459000Y68000D01*
X367000D01*
X358500Y76500D01*
X343500D01*
X338000Y82000D01*
Y102500D01*
G01X338016Y222296D02*
Y217216D01*
X334350Y213550D01*
X332550D01*
G01D02*
X329600Y216500D01*
G01X338500Y213500D02*
Y215500D01*
X339984Y216984D01*
Y222296D01*
G01X324000Y227500D02*
X325500D01*
X328490Y224510D01*
X332848D01*
G01Y230416D02*
X329084D01*
X327500Y232000D01*
G01X327923Y221577D02*
X328888Y222542D01*
X332848D01*
G01X335153Y217875D02*
X336047Y218769D01*
Y222296D01*
G01X332848Y232384D02*
X331037D01*
X327421Y236000D01*
X324000D01*
G01X333500Y251100D02*
Y249100D01*
X332600Y248200D01*
Y246600D01*
G01D02*
X333700D01*
X338016Y242284D01*
Y240504D01*
G01X332848Y234353D02*
X331147D01*
X328500Y237000D01*
Y238645D01*
G01X324300Y254700D02*
X325200Y253800D01*
Y245800D01*
X330742Y240258D01*
X332848D01*
G01X328500Y251100D02*
Y249200D01*
X327800Y248500D01*
Y246800D01*
G01D02*
X331400Y243200D01*
X334800D01*
X336047Y241953D01*
Y240504D01*
G01X336500Y295000D02*
X340980D01*
X344256Y291724D01*
Y286500D01*
G01X336525Y320500D02*
X334482Y322543D01*
X328150D01*
G01X381000Y365000D02*
Y364999D01*
X369500Y353499D01*
Y351001D01*
X365266Y346767D01*
X343768D01*
X334899Y337898D01*
X328150D01*
G01X386500Y365000D02*
X382250Y360750D01*
X379250D01*
X371500Y353000D01*
Y350000D01*
X366500Y345000D01*
X344500D01*
X334839Y335339D01*
X328150D01*
G01X336525Y325500D02*
X336127Y325102D01*
X328150D01*
G01X336525Y330500D02*
Y328650D01*
X335536Y327661D01*
X328150D01*
G01X355400Y178749D02*
X351249D01*
X346500Y174000D01*
G01X353614Y188543D02*
Y183500D01*
X355400Y181714D01*
Y178749D01*
G01X352300Y175000D02*
X352751Y174549D01*
X355400D01*
G01X355189Y188543D02*
Y185711D01*
X358200Y182700D01*
X358400D01*
G01D02*
X360400Y180700D01*
Y178749D01*
G01X344000Y212000D02*
Y215000D01*
X341953Y217047D01*
Y222296D01*
G01X345930Y217000D02*
Y220070D01*
X345152Y220848D01*
Y222542D01*
G01X357000Y233243D02*
X360243D01*
X361643Y234643D01*
X363673D01*
G01X357000Y233243D02*
X351000D01*
G01D02*
X349257D01*
X348147Y234353D01*
X345152D01*
G01Y236321D02*
X350321D01*
X351000Y237000D01*
G01D02*
X351400D01*
X352957Y238557D01*
X357000D01*
G01X363673Y239157D02*
X363073Y238557D01*
X357000D01*
G01X344256Y276500D02*
Y267480D01*
X344500Y267236D01*
Y265000D01*
G01X348100Y328500D02*
X341500D01*
G01X348100Y333500D02*
X341500D01*
G01X358250Y340050D02*
Y324050D01*
X366800Y315500D01*
X400500D01*
X408000Y308000D01*
X410000D01*
X411202Y309202D01*
X416950D01*
G01X348100Y338500D02*
X341500D01*
G01X352200Y407700D02*
Y403200D01*
G01X341796Y404153D02*
X346754D01*
X348279Y405678D01*
G01D02*
X350757Y403200D01*
X352200D01*
G01X341796Y406613D02*
X344976D01*
X348863Y410500D01*
G01D02*
X350463Y412100D01*
X352657D01*
G01X377000Y87400D02*
X373900D01*
X370500Y84000D01*
G01X469400Y96500D02*
X463000Y102900D01*
Y112000D01*
X467000Y116000D01*
Y120500D01*
X462500Y125000D01*
X439501D01*
X434501Y120000D01*
X413000D01*
X407500Y125500D01*
X387000D01*
X384500Y128000D01*
Y144500D01*
X382500Y146500D01*
Y165000D01*
X371500Y176000D01*
Y181000D01*
X373649Y183149D01*
Y185735D01*
G01X375000Y210000D02*
X379000Y214000D01*
X391000D01*
X393098Y211902D01*
G01X370500Y242600D02*
X376000D01*
G01X370500D02*
X366600Y246500D01*
X365500D01*
G01D02*
Y247500D01*
X365760Y247760D01*
Y251350D01*
G01X373240Y262650D02*
Y270860D01*
X373100Y271000D01*
G01X365000Y268000D02*
X365760Y267240D01*
Y262650D01*
G01X376500Y269000D02*
X374500Y271000D01*
X373100D01*
G01X379300Y309200D02*
X375500D01*
G01X388000Y75217D02*
Y80500D01*
X382286Y86214D01*
G01X377000Y91600D02*
X380900D01*
X381700Y92400D01*
G01D02*
X384317Y89783D01*
X388000D01*
G01X381100Y97000D02*
X381700Y96400D01*
Y92400D01*
G01X382286Y86214D02*
X381100Y87400D01*
X377000D01*
G01X386900Y97000D02*
X381100D01*
G01X393098Y137098D02*
X391130Y135130D01*
G01Y182374D02*
X393098Y180406D01*
G01X383128Y178372D02*
X385162Y180406D01*
X389161D01*
G01Y184343D02*
X387193Y186311D01*
G01X383000Y232500D02*
X387500Y228000D01*
Y221437D01*
X393098Y215839D01*
G01X380000Y210000D02*
X381902Y211902D01*
X389161D01*
G01X393098Y207965D02*
X391130Y209933D01*
G01X389161Y207965D02*
X387193Y209933D01*
G01X389161Y200091D02*
X384091D01*
G01X390000Y232500D02*
Y222874D01*
X397035Y215839D01*
G01X391900Y251000D02*
Y246800D01*
G01D02*
X400015Y238685D01*
X423915D01*
X428200Y234400D01*
Y228000D01*
X416721Y216521D01*
Y215839D01*
G01X386000Y251000D02*
Y246800D01*
G01X380100Y251000D02*
Y246800D01*
G01X392600Y268000D02*
Y272500D01*
G01D02*
Y275843D01*
X394157Y277400D01*
G01X393169Y288533D02*
Y284832D01*
X394800Y283201D01*
Y281300D01*
G01X393169Y300467D02*
Y303231D01*
X391600Y304800D01*
G01X389100Y309200D02*
X390635Y307665D01*
Y305765D01*
X391600Y304800D01*
G01X389100Y309200D02*
X383500D01*
G01X376900Y328500D02*
X383000D01*
G01X376900Y333500D02*
X383000D01*
G01X376900Y323500D02*
X383000D01*
G01X397300Y329100D02*
X392500D01*
G01X397300Y323900D02*
X392500D01*
G01X395441Y348040D02*
X388440D01*
X387000Y346600D01*
G01D02*
X383000D01*
G01X395441Y340560D02*
X392060D01*
X390000Y338500D01*
G01D02*
X387000Y341500D01*
Y342400D01*
G01X389500Y370000D02*
Y368500D01*
X391792Y366208D01*
X395088D01*
X395100Y366220D01*
X403550D01*
G01X383900Y381000D02*
X379500D01*
G01X383900Y375800D02*
X379500D01*
G01X388100D02*
Y381000D01*
G01X395000Y382000D02*
X394000Y381000D01*
X388100D01*
G01X404740Y405106D02*
X393606D01*
X388500Y400000D01*
G01X404890Y403137D02*
X396637D01*
X393500Y400000D01*
G01X388500Y391000D02*
X394731Y397231D01*
X404890D01*
G01X393500Y391000D02*
X397763Y395263D01*
X404890D01*
G01X393000Y418500D02*
X397500Y414000D01*
X408024D01*
X408494Y413530D01*
Y408860D01*
G01X412784Y137098D02*
X410816Y135130D01*
G01X408847Y141035D02*
X406879Y139067D01*
G01X404910Y141035D02*
X402942Y139067D01*
G01X410811Y131188D02*
X412784Y133161D01*
G01X406874Y131188D02*
X408847Y133161D01*
G01X399000Y135125D02*
X400973Y137098D01*
G01X399000Y131188D02*
X400973Y133161D01*
G01X395067Y135130D02*
X397035Y137098D01*
G01X412784Y144973D02*
X410816Y143005D01*
G01X412784Y141035D02*
X410816Y139067D01*
G01X408847Y144973D02*
X406879Y143005D01*
G01X408847Y160721D02*
X406879Y158753D01*
G01X395067Y182374D02*
X397035Y180406D01*
G01X412784Y172532D02*
X410816Y170564D01*
G01X406879Y182374D02*
X408847Y180406D01*
G01X402942Y182374D02*
X404910Y180406D01*
G01X400973Y184343D02*
X399005Y186311D01*
G01X400973Y188280D02*
X399005Y190248D01*
G01X408847Y184343D02*
X406879Y186311D01*
G01X408847Y192217D02*
X406879Y194185D01*
G01X397035Y184343D02*
X395067Y186311D01*
G01X397035Y188280D02*
X395067Y190248D01*
G01X400973Y196154D02*
X399005Y198122D01*
G01X395067D02*
X395794Y197394D01*
X397035Y196154D01*
G01X412784Y180406D02*
X410816Y182374D01*
G01X412784Y188280D02*
X410816Y190248D01*
G01X412784Y196154D02*
X410816Y198122D01*
G01X404910Y184343D02*
X402942Y186311D01*
G01X404910Y192217D02*
X402942Y194185D01*
G01X400973Y192217D02*
X399005Y194185D01*
G01X404910Y196154D02*
X402942Y198122D01*
G01X412784Y192217D02*
X410816Y194185D01*
G01X408847Y188280D02*
X406879Y190248D01*
G01X400973Y215839D02*
Y218139D01*
X401400Y218566D01*
Y226500D01*
X410300Y235400D01*
X416100D01*
G01X414900Y229800D02*
Y228900D01*
X404910Y218910D01*
Y215839D01*
G01X394000Y223500D02*
X396038Y221462D01*
Y219462D01*
X399000Y216500D01*
Y213875D01*
X400973Y211902D01*
G01X423000Y235400D02*
X420200Y232600D01*
X411939D01*
X403000Y223661D01*
Y213812D01*
X404910Y211902D01*
G01X420500Y229500D02*
X411000Y220000D01*
Y213686D01*
X412784Y211902D01*
G01X397035Y200091D02*
X395067Y202059D01*
G01X404910Y204028D02*
X402942Y205996D01*
G01X400973Y204028D02*
X399005Y205996D01*
G01X408847Y200091D02*
X406879Y202059D01*
G01X412784Y207965D02*
X410816Y209933D01*
G01X412784Y200091D02*
X410816Y202059D01*
G01X400973Y207965D02*
X399005Y209933D01*
G01X397035Y207965D02*
X395067Y209933D01*
G01X408847Y204028D02*
X406879Y205996D01*
G01X408847Y207965D02*
X406879Y209933D01*
G01X404910Y200091D02*
X402942Y202059D01*
G01X397035Y204028D02*
X395067Y205996D01*
G01X408847Y211902D02*
X406879Y213870D01*
G01X397800Y251000D02*
Y246800D01*
G01X420658Y215839D02*
Y217658D01*
X429855Y226855D01*
Y235307D01*
X425007Y240155D01*
X404445D01*
X397800Y246800D01*
G01X403700Y251000D02*
Y246800D01*
G01D02*
X408875Y241625D01*
X425616D01*
X431325Y235916D01*
Y226425D01*
X422500Y217600D01*
Y213997D01*
X424595Y211902D01*
G01X409300Y251000D02*
Y246800D01*
G01D02*
X413005Y243095D01*
X426225D01*
X432795Y236525D01*
Y226210D01*
X424595Y218010D01*
Y215839D01*
G01X457000Y258500D02*
X452499D01*
X451999Y258000D01*
X437000D01*
X427500Y267500D01*
X409464D01*
X402500Y274464D01*
Y302500D01*
X402000Y303000D01*
G01X483100Y272800D02*
X466300D01*
X464500Y271000D01*
Y267000D01*
X462000Y264500D01*
Y258000D01*
X459500Y255500D01*
X437000D01*
X427000Y265500D01*
X403800D01*
X396800Y272500D01*
G01X459500Y262000D02*
X453000D01*
X451170Y260170D01*
X438366D01*
X429036Y269500D01*
X411000D01*
X404500Y276000D01*
Y304000D01*
X402500Y306000D01*
Y308000D01*
G01X394800Y281300D02*
Y280800D01*
X394157Y280157D01*
Y277400D01*
G01X407500Y300500D02*
X409500D01*
X412000Y303000D01*
X433500D01*
X434500Y302000D01*
G01X408500Y316500D02*
X412440D01*
X412820Y316880D01*
X416950D01*
G01Y311761D02*
X409261D01*
X408500Y311000D01*
G01Y321998D02*
X416950D01*
G01X414941Y340760D02*
X412760D01*
X410000Y338000D01*
G01D02*
X408000Y340000D01*
Y342900D01*
G01X401500Y323900D02*
Y324000D01*
G01D02*
Y329100D01*
G01X408000Y327000D02*
X410500D01*
X412943Y324557D01*
X416950D01*
G01X408000Y327000D02*
Y326500D01*
X405500Y324000D01*
X401500D01*
G01X400559Y340560D02*
Y339940D01*
X401500Y338999D01*
Y329100D01*
G01X408000Y327000D02*
Y332000D01*
X409000Y333000D01*
X418500D01*
X420059Y334559D01*
Y340760D01*
G01X414941Y348240D02*
X409140D01*
X408000Y347100D01*
G01D02*
Y352020D01*
X406610Y353410D01*
G01X409000Y371339D02*
X403550D01*
G01X409000D02*
Y369190D01*
X418500Y359690D01*
Y354500D01*
X425000Y348000D01*
Y339674D01*
X425470Y339204D01*
X428420D01*
X428890Y338734D01*
Y337204D01*
X428420Y336734D01*
X425470D01*
X425000Y336264D01*
Y334734D01*
X425470Y334264D01*
X428420D01*
X428890Y333794D01*
Y332264D01*
X428420Y331794D01*
X425470D01*
X425000Y331324D01*
Y322601D01*
X421899Y319500D01*
X417011D01*
X416950Y319439D01*
G01X411840Y353620D02*
X412370Y354150D01*
Y360900D01*
X409609Y363661D01*
X403550D01*
G01X395000Y370000D02*
X396220Y368780D01*
X403550D01*
G01Y361102D02*
X396102D01*
X395000Y360000D01*
G01X408494Y389540D02*
Y386031D01*
X405463Y383000D01*
G01X410463D02*
Y389690D01*
G01X413500Y373500D02*
X411500D01*
X411102Y373898D01*
X403550D01*
G01Y376457D02*
X400543D01*
X395000Y382000D01*
G01X404890Y401169D02*
X399669D01*
X398500Y400000D01*
G01Y391000D02*
X400794Y393294D01*
X404740D01*
G01X403000Y418500D02*
X410000D01*
X412431Y416069D01*
Y408710D01*
G01X398000Y418500D02*
X401000Y415500D01*
X409993D01*
X410463Y415030D01*
Y408710D01*
G01X460000Y76000D02*
X454500Y70500D01*
X420000D01*
X417500Y73000D01*
Y75000D01*
G01X420500Y87900D02*
Y82000D01*
G01X431400Y82366D02*
X426366D01*
X426000Y82000D01*
X420500D01*
G01X440343Y133161D02*
Y129843D01*
X439000Y128500D01*
X427000D01*
X422000Y123500D01*
G01X424595Y137098D02*
X422627Y135130D01*
G01X420658Y137098D02*
X418690Y135130D01*
G01X416721Y137098D02*
X414753Y135130D01*
G01X424595Y133161D02*
X422627Y131193D01*
G01X420658Y133161D02*
X418690Y131193D01*
G01X428532Y144973D02*
X426564Y143005D01*
G01X428532Y133161D02*
X426564Y131193D01*
G01X428532Y141035D02*
X426564Y139067D01*
G01X424595Y141035D02*
X422627Y139067D01*
G01X424595Y144973D02*
X422627Y143005D01*
G01X420658Y144973D02*
X418690Y143005D01*
G01X416721Y144973D02*
X414753Y143005D01*
G01X416721Y141035D02*
X414753Y139067D01*
G01X428532Y148910D02*
X426564Y146942D01*
G01X424595Y152847D02*
X422627Y150879D01*
G01X420658Y152847D02*
X418690Y150879D01*
G01X420658Y148910D02*
X418690Y146942D01*
G01X416721Y148910D02*
X414753Y146942D01*
G01X428532Y152847D02*
X426564Y150879D01*
G01X428532Y176469D02*
X426564Y178437D01*
G01X422627Y182374D02*
X424595Y180406D01*
G01X426564Y182374D02*
X428532Y180406D01*
G01X416721D02*
X414753Y182374D01*
G01X428532Y184343D02*
X426564Y186311D01*
G01X428532Y188280D02*
X426564Y190248D01*
G01X420658Y196154D02*
X418690Y198122D01*
G01X424595Y192217D02*
X422627Y194185D01*
G01X424595Y184343D02*
X422627Y186311D01*
G01X416721Y188280D02*
X414753Y190248D01*
G01X420658Y188280D02*
X418690Y190248D01*
G01X420658Y184343D02*
X418690Y186311D01*
G01X416721Y184343D02*
X414753Y186311D01*
G01X416721Y196154D02*
X414753Y198122D01*
G01X428532Y192217D02*
X426564Y194185D01*
G01X424595Y196154D02*
X422627Y198122D01*
G01X420658Y192217D02*
X418690Y194185D01*
G01X425400Y229600D02*
X412784Y216984D01*
Y215839D01*
G01X420658Y204028D02*
X418690Y205996D01*
G01X416721Y204028D02*
X414753Y205996D01*
G01X416721Y207965D02*
X414753Y209933D01*
G01X415000Y246800D02*
X417235Y244565D01*
X426835D01*
X434265Y237135D01*
Y222565D01*
X430400Y218700D01*
Y213770D01*
X428532Y211902D01*
G01X420658D02*
X418690Y213870D01*
G01X416721Y200091D02*
X414753Y202059D01*
G01X428532Y200091D02*
X426564Y202059D01*
G01X428532Y204028D02*
X426564Y205996D01*
G01X428532Y207965D02*
X426564Y209933D01*
G01X424595Y200091D02*
X422627Y202059D01*
G01X424595Y204028D02*
X422627Y205996D01*
G01X420658Y207965D02*
X418690Y209933D01*
G01X420900Y251000D02*
Y246800D01*
G01X415000Y251000D02*
Y246800D01*
G01X468500Y270000D02*
X466000Y267500D01*
Y266000D01*
X463500Y263500D01*
Y257000D01*
X460500Y254000D01*
X434500D01*
X431500Y251000D01*
X420900D01*
G01X413000Y300500D02*
X414000Y299500D01*
X436500D01*
X439000Y302000D01*
G01X429442Y310075D02*
X429415D01*
X425170Y314320D01*
X416950D01*
G01X422500Y354500D02*
Y357001D01*
X424042Y358543D01*
X427450D01*
G01X434000Y349600D02*
X432100D01*
X428500Y346000D01*
G01X419000Y373500D02*
X416000Y370500D01*
Y365000D01*
X417339Y363661D01*
X427450D01*
G01X420500Y381000D02*
X422000Y379500D01*
Y373001D01*
X423662Y371339D01*
X427450D01*
G01X433500Y366500D02*
Y368000D01*
X432720Y368780D01*
X427450D01*
G01Y361102D02*
X432746D01*
X433382Y360466D01*
G01X420500Y366000D02*
X420720Y366220D01*
X427450D01*
G01X412431Y389690D02*
Y386032D01*
X415463Y383000D01*
G01X427450Y373898D02*
X432898D01*
X433500Y374500D01*
X438400D01*
G01X430000Y386500D02*
X428300Y388200D01*
Y391800D01*
X426806Y393294D01*
X424060D01*
G01X423910Y395263D02*
X428837D01*
X431900Y392200D01*
G01X431169Y401169D02*
X423910D01*
G01X431000Y411500D02*
X428000Y408500D01*
Y407000D01*
X426106Y405106D01*
X424060D01*
G01X431000Y406500D02*
Y403900D01*
X430237Y403137D01*
X423910D01*
G01X414000Y419000D02*
X416369Y416631D01*
Y408710D01*
G01X420306Y408860D02*
Y421969D01*
X422337Y424000D01*
G01X418337Y408710D02*
Y422463D01*
X416800Y424000D01*
G01X481600Y125800D02*
X480018Y127382D01*
X446118D01*
X442500Y131000D01*
Y134941D01*
X440343Y137098D01*
G01X483000Y133000D02*
X478500Y128500D01*
X447500D01*
X444280Y131720D01*
Y133161D01*
G01X440343Y144973D02*
X442311Y143005D01*
G01X436406Y137098D02*
X438374Y135130D01*
G01X444280Y141035D02*
X446248Y139067D01*
G01X445939Y135439D02*
X444280Y137098D01*
G01X436406Y144973D02*
X438374Y143005D01*
G01X436406Y141035D02*
X438374Y139067D01*
G01X434437D02*
X432469Y141035D01*
G01X434437Y135130D02*
X432469Y137098D01*
G01X434437Y131193D02*
X432469Y133161D01*
G01X440343Y148910D02*
X442311Y146942D01*
G01X434437D02*
X432469Y148910D01*
G01X434437Y150879D02*
X432469Y152847D01*
G01X436406Y148910D02*
X438374Y146942D01*
G01X440343Y152847D02*
X442311Y150879D01*
G01X444280Y152847D02*
X446248Y150879D01*
G01X444280Y180406D02*
X446248Y182374D01*
G01X436406Y176469D02*
X438374Y178437D01*
G01X432469Y180406D02*
X434437Y182374D01*
G01X436406Y180406D02*
X438374Y182374D01*
G01X444280Y184343D02*
X446248Y186311D01*
G01X440343Y184343D02*
X442311Y186311D01*
G01X436406Y188280D02*
X438374Y190248D01*
G01X432469Y188280D02*
X434437Y190248D01*
G01X432469Y192217D02*
X434437Y194185D01*
G01X436406Y196154D02*
X438374Y198122D01*
G01X440343Y188280D02*
X442311Y190248D01*
G01X440343Y192217D02*
X442311Y194185D01*
G01X432469Y196154D02*
X434437Y198122D01*
G01X444280Y196154D02*
X446248Y198122D01*
G01X436406Y184343D02*
X438374Y186311D01*
G01X444280Y192217D02*
X446248Y194185D01*
G01X440343Y196154D02*
X442311Y198122D01*
G01X436406Y207965D02*
X438374Y209933D01*
G01X436406Y204028D02*
X438374Y205996D01*
G01X436406Y200091D02*
X438374Y202059D01*
G01X440343Y207965D02*
X442311Y209933D01*
G01X436406Y215839D02*
X438374Y217807D01*
G01X432469Y215839D02*
X434437Y217807D01*
G01X432469Y200091D02*
X434437Y202059D01*
G01X432469Y211902D02*
X434437Y213870D01*
G01X440343Y204028D02*
X442311Y205996D01*
G01X444280Y204028D02*
X446248Y205996D01*
G01X444280Y200091D02*
X446248Y202059D01*
G01X432469Y207965D02*
X434437Y209933D01*
G01X440343Y215839D02*
Y223843D01*
X439500Y224686D01*
Y232500D01*
X443500Y236500D01*
G01X449000Y232500D02*
X446000Y229500D01*
Y223220D01*
X444280Y221500D01*
Y215839D01*
G01X440343Y211902D02*
X442000Y213559D01*
Y229500D01*
X443500Y231000D01*
Y231500D01*
G01X444280Y211902D02*
X446000Y213622D01*
Y220000D01*
X449000Y223000D01*
Y227500D01*
G01X439500Y241900D02*
Y236000D01*
X436500Y233000D01*
G01X443500Y231500D02*
X447000Y235000D01*
X450500D01*
X451000Y235500D01*
Y239900D01*
X453000Y241900D01*
G01X444000D02*
X439500D01*
G01X443500Y236500D02*
X444000D01*
X446500Y239000D01*
Y239900D01*
X448500Y241900D01*
G01X447000Y283000D02*
X445353Y284647D01*
X441975D01*
G01X446000Y294000D02*
Y292597D01*
X443956Y290553D01*
X441975D01*
G01Y292521D02*
Y297025D01*
X441500Y297500D01*
G01X452400Y299500D02*
X443500D01*
X441500Y297500D01*
G01X440850Y314320D02*
X433000D01*
G01X440850Y306643D02*
X435143D01*
G01X454000Y312500D02*
X447061Y319439D01*
X440850D01*
G01X448500Y311500D02*
X448239Y311761D01*
X440850D01*
G01Y316880D02*
X436120D01*
X434000Y319000D01*
Y328000D01*
G01X451000Y306500D02*
X449500D01*
X446798Y309202D01*
X440850D01*
G01X440000Y332500D02*
X439000Y333500D01*
Y334500D01*
X434000Y339500D01*
Y345400D01*
G01X440850Y321998D02*
X447000D01*
G01X434000Y349600D02*
X436250D01*
X439800Y353150D01*
G01X438400Y370000D02*
Y374500D01*
G01X443500Y361850D02*
X441150D01*
X438500Y364500D01*
G01D02*
X438400Y364600D01*
Y370000D01*
G01X435400Y386500D02*
X430000D01*
G01X450000Y411500D02*
X447500D01*
X445000Y409000D01*
X442500D01*
X440000Y406500D01*
X439600D01*
G01X431900Y392200D02*
X432600Y391500D01*
X435400D01*
G01Y401500D02*
X431500D01*
X431169Y401169D01*
G01X435400Y406500D02*
X431000D01*
G01X450000Y416500D02*
X447500Y414000D01*
X442100D01*
X439600Y411500D01*
G01X435400D02*
X431000D01*
G01X469400Y91500D02*
X467500D01*
X465500Y89500D01*
X461500D01*
X458500Y86500D01*
G01X452154Y141035D02*
X454122Y139067D01*
G01X456091Y141035D02*
X458059Y139067D01*
G01X460028Y137098D02*
X461996Y135130D01*
G01X452154Y137098D02*
X454122Y135130D01*
G01X457844Y135345D02*
X456091Y137098D01*
G01X449876Y131502D02*
X448217Y133161D01*
G01X452154D02*
X454122Y131193D01*
G01X456091Y144973D02*
X458059Y143005D01*
G01X460028Y144973D02*
X461996Y143005D01*
G01X448217Y141035D02*
X450185Y139067D01*
G01X456091Y160721D02*
X458059Y158753D01*
G01X452154Y160721D02*
X454122Y158753D01*
G01X452154Y164658D02*
X454122Y162690D01*
G01X456091Y164658D02*
X458059Y162690D01*
G01X460028Y164658D02*
X461996Y162690D01*
G01X452154Y152847D02*
X454122Y150879D01*
G01X456091Y148910D02*
X458059Y146942D01*
G01X460028Y152847D02*
X461996Y150879D01*
G01X460028Y148910D02*
X461996Y146942D01*
G01X448217Y148910D02*
X450185Y146942D01*
G01X452154Y148910D02*
X454122Y146942D01*
G01X452154Y156784D02*
X454122Y154816D01*
G01X456091Y156784D02*
X458059Y154816D01*
G01X460028Y156784D02*
X461996Y154816D01*
G01X448217Y152847D02*
X450185Y150879D01*
G01X456091Y176469D02*
X458059Y178437D01*
G01X450185Y182374D02*
X448217Y180406D01*
G01X481000Y172500D02*
X479000Y174500D01*
X454122D01*
X452154Y172532D01*
G01X454122Y166627D02*
X452374Y168374D01*
X452154Y168595D01*
G01Y180406D02*
X454122Y182374D01*
G01X452154Y176469D02*
X454122Y178437D01*
G01X456091Y180406D02*
X458059Y182374D01*
G01X460028Y172532D02*
X461996Y170564D01*
G01X460028Y176469D02*
X461996Y178437D01*
G01X456091Y168595D02*
X458060Y170564D01*
G01X460028Y168595D02*
X461996Y166627D01*
G01X456091Y188280D02*
X458059Y190248D01*
G01X460028Y184343D02*
X461996Y186311D01*
G01X452154Y192217D02*
X454122Y194185D01*
G01X448217Y192217D02*
X450185Y194185D01*
G01X452154Y188280D02*
X454122Y190248D01*
G01X456091Y184343D02*
X458059Y186311D01*
G01X452154Y196154D02*
X454122Y198122D01*
G01X456091Y196154D02*
X458059Y198122D01*
G01X460028Y188280D02*
X461996Y190248D01*
G01X460028Y196154D02*
X461996Y198122D01*
G01X460028Y192217D02*
X461996Y194185D01*
G01X448217Y184343D02*
X450185Y186311D01*
G01Y190248D02*
X448217Y188280D01*
G01X452154Y215839D02*
X454122Y217807D01*
G01X460028Y207965D02*
X461996Y209933D01*
G01X460028Y204028D02*
X461996Y205996D01*
G01X460028Y211902D02*
X461996Y213870D01*
G01X456091Y200091D02*
X458059Y202059D01*
G01X456091Y204028D02*
X458059Y205996D01*
G01X452154Y207965D02*
X454122Y209933D01*
G01X456091Y207965D02*
X458059Y209933D01*
G01X460028Y215839D02*
X461996Y217807D01*
G01X448217Y207965D02*
X450185Y209933D01*
G01X448217Y211902D02*
X450185Y213870D01*
G01X452154Y211902D02*
X454122Y213870D01*
G01X456091Y215839D02*
X458059Y217807D01*
G01X448217Y200091D02*
X450185Y202059D01*
G01X452154Y200091D02*
X454122Y202059D01*
G01X448217Y204028D02*
X450185Y205996D01*
G01X449000Y232500D02*
X453400D01*
X453500Y232400D01*
G01X449000Y227500D02*
X453500D01*
X456500Y230500D01*
Y233239D01*
X459735Y236474D01*
Y239236D01*
X462000Y241501D01*
Y241900D01*
G01X461000Y230000D02*
X464900D01*
X465000Y229900D01*
G01Y234100D02*
X461400D01*
X461000Y234500D01*
G01X448500Y246100D02*
Y250000D01*
G01X457500Y241900D02*
Y237400D01*
G01X453500Y236600D02*
X456700D01*
X457500Y237400D01*
G01X453000Y246100D02*
Y250000D01*
G01X468500Y264500D02*
X467500D01*
X465500Y262500D01*
Y248000D01*
X463600Y246100D01*
X462000D01*
G01X452400Y284500D02*
X448500D01*
X447000Y283000D01*
G01X531000Y285500D02*
X525100Y291400D01*
X463600D01*
X460800Y294200D01*
G01X452400Y294500D02*
X447903D01*
X447403Y294000D01*
X446000D01*
G01X456600Y299500D02*
X458662D01*
X464243Y293919D01*
X524419D01*
X526000Y295500D01*
G01X456600Y299500D02*
Y305400D01*
X456500Y305500D01*
G01X447000Y321998D02*
X451198D01*
X451200Y322000D01*
G01X478000Y78000D02*
X479398Y76602D01*
X488550D01*
G01Y81720D02*
X484720D01*
X483500Y80500D01*
X477000D01*
X475000Y78500D01*
X473600D01*
G01X475500Y82500D02*
X474500D01*
X473600Y81600D01*
Y78500D01*
G01Y86500D02*
X481000D01*
X483898Y89398D01*
X488550D01*
G01X470500Y82500D02*
X473600Y85600D01*
Y86500D01*
G01X479500Y92500D02*
X483671D01*
X484214Y91957D01*
X488550D01*
G01X479500Y92500D02*
X477236D01*
X476236Y91500D01*
X473600D01*
G01D02*
Y96500D01*
G01X463965Y141035D02*
X465933Y139067D01*
G01X467902Y141035D02*
X469870Y139067D01*
G01X467902Y133161D02*
X469870Y131193D01*
G01X471839Y133161D02*
X473807Y131193D01*
G01X463965Y137098D02*
X465933Y135130D01*
G01X463965Y144973D02*
X465933Y143005D01*
G01X467902Y144973D02*
X469870Y143005D01*
G01X471839Y152847D02*
X473807Y150879D01*
G01X471839Y156784D02*
X473807Y154816D01*
G01X485000Y154000D02*
X480000Y159000D01*
X469623D01*
X467902Y160721D01*
G01X463965Y156784D02*
X465933Y154816D01*
G01X463965Y164658D02*
X465933Y162690D01*
G01X467902Y164658D02*
X469560Y163000D01*
X475000D01*
G01D02*
X488400D01*
G01X491000Y154000D02*
X489300D01*
X482579Y160721D01*
X471839D01*
G01X463965D02*
X465933Y158753D01*
G01X463965Y152847D02*
X465933Y150879D01*
G01X467902Y152847D02*
X469870Y150879D01*
G01X477500Y170500D02*
X475595Y168595D01*
X471839D01*
G01X463965Y172532D02*
X465933Y170564D01*
G01X463965Y176469D02*
X465933Y178437D01*
G01X471839Y180406D02*
X473807Y182374D01*
G01X467902Y180406D02*
X469870Y182374D01*
G01Y166627D02*
X467902Y168595D01*
G01Y172532D02*
X469870Y170564D01*
G01X471839Y172532D02*
X473807Y170564D01*
G01X471839Y176469D02*
X473807Y178437D01*
G01X463965Y180406D02*
X465933Y182374D01*
G01X463965Y192217D02*
X465933Y194185D01*
G01X463965Y184343D02*
X465933Y186311D01*
G01X471839Y192217D02*
X475775D01*
X479992Y188000D01*
X499000D01*
X502000Y185000D01*
Y173000D01*
X507000Y168000D01*
Y122499D01*
X520849Y108650D01*
X521805D01*
X522275Y108180D01*
Y105430D01*
X522745Y104960D01*
X524275D01*
X524745Y105430D01*
Y108180D01*
X525215Y108650D01*
X526745D01*
X527215Y108180D01*
Y105430D01*
X527685Y104960D01*
X529215D01*
X529685Y105430D01*
Y108180D01*
X530155Y108650D01*
X531850D01*
X535500Y105000D01*
Y87500D01*
X536500Y86500D01*
Y84500D01*
G01X471839Y196154D02*
X474846D01*
X481000Y190000D01*
X500501D01*
X504000Y186501D01*
Y173500D01*
X509000Y168500D01*
Y123340D01*
X521682Y110658D01*
X532682D01*
X537500Y105840D01*
Y88000D01*
X539000Y86500D01*
Y81500D01*
X536500Y79000D01*
G01X467902Y188280D02*
X469870Y190248D01*
G01X467902Y184343D02*
X469870Y186311D01*
G01X471839Y188280D02*
X473807Y190248D01*
G01X467902Y192217D02*
X469870Y194185D01*
G01X463965Y196154D02*
X465933Y198122D01*
G01X480288Y203788D02*
X478908Y202408D01*
X470219D01*
X467902Y200091D01*
G01X480288Y203788D02*
X480790D01*
X484078Y200500D01*
X486000D01*
X488000Y202500D01*
X488400D01*
G01X471839Y200091D02*
X472518Y200770D01*
X481342D01*
X483871Y198241D01*
G01X467902Y211902D02*
X469870Y213870D01*
G01X467902Y207965D02*
X469870Y209933D01*
G01X463965Y200091D02*
X465933Y202059D01*
G01X463965Y204028D02*
X465933Y205996D01*
G01X471839Y211902D02*
X473807Y213870D01*
G01X471839Y215839D02*
X473807Y217807D01*
G01X467902Y204028D02*
X469870Y205996D01*
G01X471839Y207965D02*
X473807Y209933D01*
G01X478656Y382953D02*
X472653D01*
X471100Y381400D01*
Y375400D01*
X465500Y369800D01*
Y357000D01*
X467000Y355500D01*
G01X473500Y354600D02*
X467900D01*
X467000Y355500D01*
G01X478500Y354600D02*
X473500D01*
G01X478500Y346000D02*
Y350400D01*
G01X478656Y375079D02*
X476079D01*
X470462Y369462D01*
G01X483500Y354600D02*
X478700Y359400D01*
X469800D01*
X468100Y361100D01*
Y367100D01*
X470462Y369462D01*
G01X482000Y83500D02*
X482780Y84280D01*
X488550D01*
G01X493700Y79161D02*
X488550D01*
G01Y86839D02*
X494161D01*
X496000Y85000D01*
G01X495900Y133500D02*
X490970D01*
G01X495900Y143000D02*
Y138500D01*
G01D02*
X490970D01*
G01X497000Y154000D02*
Y158600D01*
X492600Y163000D01*
G01X488400Y167500D02*
Y163000D01*
G01Y172000D02*
Y176500D01*
G01Y172000D02*
X481500D01*
X481000Y172500D01*
G01X507000Y188500D02*
X504000Y191500D01*
Y193500D01*
X497533Y199967D01*
X495067D01*
X492600Y197500D01*
G01X483871Y198241D02*
Y195652D01*
X484523Y195000D01*
X487930D01*
X488400Y195470D01*
Y197500D01*
G01X497500Y214000D02*
X497000Y213500D01*
Y210999D01*
X493001Y207000D01*
X492600D01*
G01Y202500D02*
X498500D01*
X506000Y195000D01*
Y193500D01*
X507000Y192500D01*
G01X488400Y211500D02*
Y207000D01*
G01Y211500D02*
X483000D01*
X482000Y212500D01*
G01X496100Y268600D02*
Y263700D01*
X496000Y263600D01*
G01X488900Y272800D02*
X483100D01*
G01X496100Y268600D02*
X488900D01*
G01X496100D02*
X497635Y270135D01*
X499535D01*
X500500Y271100D01*
G01X488500Y350400D02*
X491000Y347900D01*
Y343000D01*
X523000Y311000D01*
X582000D01*
X584500Y308500D01*
Y299499D01*
X585764Y298235D01*
Y276736D01*
X591000Y271500D01*
G01X493500Y359000D02*
Y354600D01*
G01D02*
X488500D01*
G01X483500Y350400D02*
Y346001D01*
X483501Y346000D01*
G01X488500Y359000D02*
Y359921D01*
X491549Y362970D01*
Y367205D01*
G01Y375079D02*
X496921D01*
X501270Y370730D01*
Y359470D01*
X500800Y359000D01*
X498699D01*
X498229Y359470D01*
Y362030D01*
X497759Y362500D01*
X496229D01*
X495759Y362030D01*
Y359470D01*
X495289Y359000D01*
X493500D01*
G01X503000Y354600D02*
Y371500D01*
X499000Y375500D01*
Y378000D01*
X494047Y382953D01*
X491549D01*
G01X504000Y64500D02*
Y77702D01*
X508018Y81720D01*
X512450D01*
G01X508500Y64500D02*
X508000Y65000D01*
Y73673D01*
X508370Y74043D01*
X512450D01*
G01X524900Y82000D02*
X522500D01*
X520500Y84000D01*
X519500D01*
X516661Y86839D01*
X512450D01*
G01X524900Y76000D02*
X523096D01*
X522000Y77096D01*
Y77530D01*
X521030Y78500D01*
X516999D01*
X516338Y79161D01*
X512450D01*
G01X519500Y81500D02*
X516720Y84280D01*
X512450D01*
G01X519500Y75500D02*
X518398Y76602D01*
X512450D01*
G01Y89398D02*
X519102D01*
X520000Y88500D01*
Y87000D01*
G01X507000Y192500D02*
X513830D01*
X519890Y198560D01*
Y218092D01*
X519420Y218562D01*
X515400D01*
X514930Y219032D01*
Y220562D01*
X515400Y221032D01*
X519420D01*
X519890Y221502D01*
Y223032D01*
X519420Y223502D01*
X515400D01*
X514930Y223972D01*
Y225502D01*
X515400Y225972D01*
X519420D01*
X519890Y226442D01*
Y227972D01*
X519420Y228442D01*
X515400D01*
X514930Y228912D01*
Y230442D01*
X515400Y230912D01*
X519420D01*
X519890Y231382D01*
Y233389D01*
X538268Y251767D01*
X601267D01*
X604000Y254500D01*
G01X507000Y188500D02*
X513800D01*
X521740Y196440D01*
Y232740D01*
X539000Y250000D01*
X605000D01*
X609500Y254500D01*
G01X504833Y272669D02*
X502069D01*
X500500Y271100D01*
G01X591000Y291500D02*
Y296500D01*
X587000Y300500D01*
Y309000D01*
X583000Y313000D01*
X524500D01*
X515598Y321902D01*
Y322566D01*
X518184Y325152D01*
Y325816D01*
X517101Y326899D01*
X516437D01*
X513851Y324313D01*
X513187D01*
X512104Y325396D01*
Y326060D01*
X514690Y328646D01*
Y329310D01*
X513607Y330393D01*
X512943D01*
X510357Y327807D01*
X509693D01*
X508610Y328890D01*
Y329554D01*
X511196Y332140D01*
Y332804D01*
X510113Y333887D01*
X509449D01*
X506863Y331301D01*
X506199D01*
X505116Y332384D01*
Y333048D01*
X507052Y334984D01*
Y335648D01*
X505969Y336731D01*
X505305D01*
X503369Y334795D01*
X502705D01*
X501000Y336500D01*
Y347900D01*
X498500Y350400D01*
G01Y354600D02*
X503000D01*
G01X536500Y79000D02*
X526000D01*
X524900Y77900D01*
Y76000D01*
G01Y82000D02*
Y83000D01*
X526400Y84500D01*
X536500D01*
G01X524900Y87000D02*
X520000D01*
G01X531500Y281100D02*
Y285000D01*
X531000Y285500D01*
G01X531500Y276900D02*
X527000D01*
G01D02*
Y272543D01*
X526957Y272500D01*
G01X516767Y272669D02*
X519069D01*
X522600Y276200D01*
G01D02*
X524000Y274800D01*
Y273500D01*
X525000Y272500D01*
X526957D01*
G01X528300Y420953D02*
X532300Y424953D01*
Y425700D01*
G01X556533Y65931D02*
X552431D01*
X550000Y63500D01*
X549000D01*
G01D02*
X546043D01*
G01X549500Y69400D02*
X545000D01*
X544600Y69000D01*
G01X556533Y67900D02*
X551000D01*
X549500Y69400D01*
G01X551000Y232957D02*
X547057D01*
X546500Y232400D01*
G01X552087Y221996D02*
Y224104D01*
X548158Y228033D01*
G01X546500Y232400D02*
Y229691D01*
X548158Y228033D01*
G01X576000Y246500D02*
X574500Y248000D01*
X557900D01*
X546500Y236600D01*
G01X550544Y272100D02*
X541982D01*
X540318Y270436D01*
G01X543504Y421654D02*
X548829Y416329D01*
G01X548500Y411000D02*
X551279Y413779D01*
X555315D01*
G01X543504D02*
X538558D01*
G01X555315Y427558D02*
X550369D01*
G01X543504D02*
X538558D01*
G01X554547Y221996D02*
Y226554D01*
X553122Y227979D01*
G01X555500Y232400D02*
Y230357D01*
X553122Y227979D01*
G01X566000Y347000D02*
X571700D01*
X572000Y346700D01*
G01X559271Y365826D02*
X561174D01*
X564500Y362500D01*
Y361000D01*
X568000Y357500D01*
Y356700D01*
G01X572000Y390700D02*
X567700D01*
X564800Y387800D01*
Y385300D01*
X561074Y381574D01*
X559271D01*
G01X555569Y383456D02*
Y388051D01*
G01D02*
X556000Y388482D01*
Y389564D01*
X555900Y389664D01*
Y391500D01*
G01Y396000D02*
Y396900D01*
X560000Y401000D01*
G01X555900Y391500D02*
Y396000D01*
G01X567126Y421654D02*
Y417500D01*
G01X555315Y421654D02*
Y417500D01*
G01X567126Y413779D02*
X562180D01*
G01X567126Y427558D02*
X562180D01*
G01X577200Y70000D02*
X574770Y67570D01*
X572870D01*
G01X568467Y65931D02*
X571231D01*
X572870Y67570D01*
G01X577500Y75400D02*
Y70300D01*
X577200Y70000D01*
G01X580000Y104800D02*
Y101000D01*
X588000Y93000D01*
X595000D01*
X595600Y93600D01*
Y96500D01*
G01X571056Y262100D02*
X581400D01*
G01X571056Y272100D02*
X581400D01*
G01X571056Y282100D02*
X581400D01*
G01X571056Y302100D02*
X581500D01*
G01X572000Y356700D02*
Y351700D01*
G01Y346700D02*
Y351700D01*
G01X568000Y356700D02*
X572000D01*
G01Y390700D02*
Y396300D01*
X571800Y396500D01*
G01X578937Y421654D02*
Y417500D01*
G01X572500Y413500D02*
X572779Y413779D01*
X578937D01*
G01Y427558D02*
X573991D01*
G01X608450Y105780D02*
X602280D01*
X599000Y102500D01*
X595600D01*
G01X586500Y107000D02*
X588000Y105500D01*
X595130D01*
X595600Y105030D01*
Y102500D01*
G01X591400Y112500D02*
Y108000D01*
G01X608450Y103220D02*
X602320D01*
X595600Y96500D01*
G01X608450Y108340D02*
X604860D01*
X600850Y112350D01*
G01X595600Y108000D02*
X596500D01*
X600850Y112350D01*
G01X591400Y112500D02*
X586500D01*
G01X592000Y146000D02*
X593063Y147063D01*
X599450D01*
G01Y157063D02*
X592000D01*
G01Y178000D02*
X592500D01*
X593437Y177063D01*
X599450D01*
G01X592000Y168000D02*
X592937Y167063D01*
X599450D01*
G01X591902Y200300D02*
Y195065D01*
G01X596902D02*
Y199802D01*
X597000Y199900D01*
G01X587500Y190000D02*
X591037D01*
X591902Y190865D01*
G01X602500Y183000D02*
Y184000D01*
X601902Y184598D01*
Y190865D01*
G01Y195065D02*
Y200100D01*
G01X601953Y204418D02*
X604482D01*
X606902Y201998D01*
Y200400D01*
G01X596047Y204418D02*
Y202947D01*
X593400Y200300D01*
X591902D01*
G01X598016Y204418D02*
Y200916D01*
X597000Y199900D01*
G01X599984Y204418D02*
Y201316D01*
X601200Y200100D01*
X601902D01*
G01X599984Y214382D02*
Y217517D01*
X597001Y220500D01*
X594153D01*
G01X589953Y233000D02*
Y236600D01*
G01X594153Y223900D02*
Y228402D01*
G01D02*
Y233000D01*
G01Y220500D02*
Y223900D01*
G01Y233000D02*
Y237653D01*
X595500Y239000D01*
G01X601844Y261500D02*
X591000D01*
G01X601844Y271500D02*
X591000D01*
G01Y278500D02*
Y279500D01*
X593000Y281500D01*
X601844D01*
G01X590500Y301500D02*
X601844D01*
G01Y291500D02*
X591000D01*
G01X602559Y421654D02*
Y417500D01*
G01X590748Y413779D02*
Y418725D01*
G01X602559Y413779D02*
X597613D01*
G01X602559Y427558D02*
X597613D01*
G01X622000Y146500D02*
X621437Y147063D01*
X614648D01*
G01Y157063D02*
X621937D01*
X622000Y157000D01*
G01Y175500D02*
X620437Y177063D01*
X614648D01*
G01Y167063D02*
X622035D01*
G01X606902Y195065D02*
Y200400D01*
G01Y190865D02*
Y186000D01*
G01X614370Y421654D02*
Y417500D01*
G01Y413779D02*
X609424D01*
G01X614370Y427558D02*
X609424D01*
G01X633500Y108000D02*
X637900D01*
G01X626550Y105780D02*
X631280D01*
X633500Y108000D01*
G01Y102000D02*
X637900D01*
G01X626550Y103220D02*
X632280D01*
X633500Y102000D01*
G01Y96500D02*
X637900D01*
G01X626550Y100660D02*
X628840D01*
X633000Y96500D01*
X633500D01*
G01X633000Y267000D02*
Y271030D01*
X632530Y271500D01*
X622356D01*
G01Y261500D02*
X632000D01*
X633000Y262500D01*
Y267000D01*
G01X622356Y281500D02*
X631500D01*
X633000Y283000D01*
Y286500D01*
G01D02*
Y290000D01*
X631500Y291500D01*
X622356D01*
G54D18*
X27250Y95650D03*
X19750Y104350D03*
X27250D03*
X19750Y218350D03*
X27250D03*
Y209650D03*
G54D45*
X168000Y301500D03*
X510800Y270700D03*
X562500Y67900D03*
G54D72*
X357000Y233243D03*
Y238557D03*
G54D90*
X431400Y90634D03*
X441400D03*
X436400D03*
X431400Y82366D03*
X436400D03*
X441400D03*
G54D36*
X95750Y65360D03*
Y72840D03*
Y69100D03*
X107050Y72840D03*
Y65360D03*
G54D54*
X160860Y390104D03*
Y403096D03*
X339040Y407696D03*
Y394704D03*
G54D63*
X276986Y175184D03*
Y177152D03*
Y179121D03*
Y181089D03*
Y185026D03*
Y186995D03*
Y188963D03*
Y190932D03*
Y183058D03*
Y192900D03*
X292734Y175184D03*
Y177152D03*
Y179121D03*
Y181089D03*
Y186995D03*
Y188963D03*
Y190932D03*
Y192900D03*
Y183058D03*
Y185026D03*
G54D27*
X70500Y142244D03*
X80500D03*
X70500Y162756D03*
X80500D03*
G54D81*
X395588Y300467D03*
G54D28*
X74593Y209100D03*
X86207D03*
G54D19*
X20550Y95650D03*
Y209650D03*
G54D55*
X166962Y397880D03*
Y395320D03*
X332938Y399920D03*
Y402480D03*
G54D91*
X441975Y282429D03*
G54D73*
X348100Y323500D03*
Y328500D03*
Y338500D03*
Y333500D03*
X376900D03*
Y338500D03*
Y323500D03*
Y328500D03*
G54D64*
X305708Y15731D03*
G54D37*
X95000Y84500D03*
X110500Y414500D03*
X578000Y116500D03*
G54D46*
X162033Y297112D03*
X504833Y266312D03*
X556533Y63512D03*
G54D82*
X395588Y288533D03*
G54D92*
X435600Y287600D03*
G54D29*
X80400Y215104D03*
G54D83*
X400559Y340560D03*
X398000D03*
X395441D03*
Y348040D03*
X398000D03*
X400559D03*
X420059Y340760D03*
X417500D03*
X414941D03*
Y348240D03*
X417500D03*
X420059D03*
G54D65*
X304250Y322543D03*
Y325102D03*
Y335339D03*
Y327661D03*
Y332780D03*
Y337898D03*
Y330220D03*
Y340457D03*
X328150Y335339D03*
Y330220D03*
Y337898D03*
Y332780D03*
Y327661D03*
Y325102D03*
Y322543D03*
Y340457D03*
X403550Y358543D03*
Y361102D03*
Y363661D03*
Y366220D03*
Y368780D03*
Y371339D03*
Y373898D03*
Y376457D03*
X416950Y306643D03*
Y309202D03*
Y311761D03*
Y314320D03*
Y316880D03*
Y319439D03*
Y321998D03*
Y324557D03*
X427450Y371339D03*
Y368780D03*
Y366220D03*
Y363661D03*
Y361102D03*
Y358543D03*
Y376457D03*
Y373898D03*
X440850Y319439D03*
Y316880D03*
Y314320D03*
Y311761D03*
Y309202D03*
Y306643D03*
Y324557D03*
Y321998D03*
X488550Y74043D03*
Y76602D03*
Y79161D03*
Y81720D03*
Y84280D03*
Y86839D03*
Y89398D03*
Y91957D03*
X512450Y76602D03*
Y74043D03*
Y91957D03*
Y89398D03*
Y86839D03*
Y84280D03*
Y81720D03*
Y79161D03*
G54D38*
X89848Y263200D03*
X95248D03*
X158800Y377600D03*
X153400D03*
X341100Y420200D03*
X346500D03*
X361800Y147000D03*
X367200D03*
X362800Y220500D03*
X368200D03*
X370800Y309900D03*
X365400D03*
X459800Y386000D03*
X465200D03*
X523700Y172500D03*
X518300D03*
X531400Y390200D03*
X547900Y356900D03*
X536800Y390200D03*
X553300Y356900D03*
X603300Y232400D03*
X608700D03*
G54D47*
X162033Y299531D03*
Y301500D03*
Y303469D03*
X173967D03*
Y301500D03*
Y299531D03*
X504833Y268731D03*
X516767D03*
X504833Y270700D03*
Y272669D03*
X516767D03*
Y270700D03*
X556533Y69869D03*
X568467D03*
X556533Y67900D03*
Y65931D03*
X568467Y67900D03*
Y65931D03*
G54D74*
X363673Y232557D03*
Y234643D03*
Y241243D03*
Y239157D03*
X398200Y310043D03*
Y307957D03*
X551000Y232957D03*
Y235043D03*
X564000Y232957D03*
Y235043D03*
X569500Y233457D03*
Y235543D03*
G54D56*
X158104Y395616D03*
Y399553D03*
Y393647D03*
Y397584D03*
X341796Y402184D03*
Y398247D03*
Y404153D03*
Y400216D03*
G54D93*
X447200Y353150D03*
X439800D03*
X443500Y361850D03*
G54D75*
X388000Y75217D03*
Y89783D03*
X398000Y75217D03*
X408000D03*
Y89783D03*
X398000D03*
G54D84*
X410463Y389690D03*
Y408710D03*
X418337Y389690D03*
X416369D03*
X414400D03*
X412431D03*
Y408710D03*
X414400D03*
X416369D03*
X418337D03*
G54D39*
X89400Y320136D03*
Y337853D03*
Y335884D03*
Y333916D03*
Y331947D03*
Y329979D03*
Y328010D03*
Y326042D03*
Y324073D03*
Y322105D03*
Y349664D03*
Y347695D03*
Y345727D03*
Y343758D03*
Y341790D03*
Y339821D03*
X135200Y320136D03*
Y322105D03*
Y324073D03*
Y326042D03*
Y328010D03*
Y329979D03*
Y331947D03*
Y333916D03*
Y335884D03*
Y337853D03*
Y345727D03*
Y347695D03*
Y349664D03*
Y339821D03*
Y341790D03*
Y343758D03*
G54D48*
X162033Y305888D03*
X504833Y275088D03*
X556533Y72288D03*
G54D66*
X305000Y374787D03*
Y398213D03*
G54D57*
X183661Y13781D03*
X179724D03*
X199409D03*
X195472D03*
X187598D03*
X191535D03*
X219094D03*
X207283D03*
X215157D03*
X211220D03*
X203346D03*
X230905D03*
X234842D03*
X250590D03*
X238779D03*
X242716D03*
X254527D03*
X246653D03*
X258464D03*
X262401D03*
X270275D03*
X266338D03*
X289960D03*
X274212D03*
X278149D03*
X286023D03*
X282086D03*
X301771D03*
X293897D03*
X297834D03*
X309645D03*
G54D85*
X408494Y389540D03*
Y408860D03*
X420306Y389540D03*
Y408860D03*
G54D76*
X389161Y141035D03*
Y137098D03*
X393098Y141035D03*
Y137098D03*
Y133161D03*
X389161D03*
X393098Y144973D03*
X389161D03*
X393098Y156784D03*
Y148910D03*
X389161Y156784D03*
Y148910D03*
X393098Y152847D03*
X389161D03*
X393098Y160721D03*
X389161D03*
X393098Y164658D03*
Y172532D03*
X389161Y164658D03*
Y176469D03*
X393098D03*
X389161Y172532D03*
X393098Y180406D03*
X389161D03*
X393098Y168595D03*
X389161D03*
X393098Y184343D03*
X389161Y196154D03*
Y188280D03*
Y192217D03*
X393098Y188280D03*
Y192217D03*
Y196154D03*
X389161Y184343D03*
Y215839D03*
X393098Y204028D03*
Y211902D03*
X389161D03*
X393098Y215839D03*
X389161Y200091D03*
Y204028D03*
X393098Y207965D03*
X389161D03*
X393098Y200091D03*
X408847Y137098D03*
X397035Y133161D03*
Y144973D03*
X404910D03*
X400973D03*
Y141035D03*
X397035D03*
X408847D03*
X404910D03*
X408847Y133161D03*
X404910Y137098D03*
X400973D03*
X404910Y133161D03*
X400973D03*
X397035Y137098D03*
X408847Y144973D03*
X397035Y160721D03*
X408847Y156784D03*
X404910Y160721D03*
X400973Y152847D03*
X408847Y148910D03*
X404910Y156784D03*
Y148910D03*
X400973Y160721D03*
X397035Y152847D03*
X408847Y160721D03*
Y152847D03*
X404910D03*
X400973Y156784D03*
Y148910D03*
X397035Y156784D03*
Y148910D03*
X408847Y176469D03*
X404910D03*
X408847Y164658D03*
X400973Y168595D03*
X408847Y172532D03*
X404910Y164658D03*
Y172532D03*
X400973Y180406D03*
Y176469D03*
X397035D03*
Y168595D03*
Y180406D03*
X404910D03*
X408847D03*
Y168595D03*
X404910D03*
X400973Y164658D03*
Y172532D03*
X397035Y164658D03*
Y172532D03*
X404910Y188280D03*
X408847Y196154D03*
X397035Y192217D03*
X400973Y184343D03*
Y188280D03*
X404910Y192217D03*
X400973D03*
X404910Y184343D03*
X397035D03*
Y188280D03*
X408847Y192217D03*
X404910Y196154D03*
X408847Y184343D03*
X400973Y196154D03*
X397035D03*
X408847Y188280D03*
Y215839D03*
X400973Y200091D03*
X397035Y211902D03*
X404910Y207965D03*
Y211902D03*
X400973D03*
X404910Y215839D03*
X400973D03*
X397035D03*
X400973Y207965D03*
X397035D03*
X408847Y204028D03*
Y207965D03*
Y200091D03*
X404910D03*
Y204028D03*
X400973D03*
X397035Y200091D03*
Y204028D03*
X408847Y211902D03*
X420658Y141035D03*
X428532Y137098D03*
X416721Y133161D03*
X424595Y137098D03*
X420658D03*
X416721D03*
X412784D03*
X424595Y133161D03*
X420658D03*
X412784D03*
X428532Y144973D03*
Y133161D03*
Y141035D03*
X424595D03*
Y144973D03*
X420658D03*
X416721D03*
X412784D03*
X416721Y141035D03*
X412784D03*
X416721Y152847D03*
X428532Y156784D03*
X424595Y160721D03*
X420658Y156784D03*
X416721Y160721D03*
X428532D03*
X424595Y156784D03*
Y148910D03*
X420658Y160721D03*
X416721Y156784D03*
X412784Y160721D03*
Y156784D03*
Y152847D03*
Y148910D03*
X428532D03*
X424595Y152847D03*
X420658D03*
Y148910D03*
X416721D03*
X428532Y152847D03*
X420658Y180406D03*
Y164658D03*
X416721Y168595D03*
X428532Y172532D03*
X420658D03*
X424595Y176469D03*
X416721D03*
X424595Y168595D03*
Y172532D03*
X420658Y176469D03*
Y168595D03*
X416721Y164658D03*
Y172532D03*
X412784Y164658D03*
Y176469D03*
Y168595D03*
X424595Y164658D03*
X428532Y180406D03*
X416721D03*
X412784D03*
X424595D03*
X428532Y164658D03*
Y168595D03*
X412784Y172532D03*
X428532Y176469D03*
Y196154D03*
X416721Y192217D03*
X424595Y188280D03*
X412784Y184343D03*
X416721Y196154D03*
X420658Y188280D03*
X416721D03*
X412784Y196154D03*
X420658Y184343D03*
X416721D03*
X412784Y188280D03*
Y192217D03*
X428532D03*
X424595D03*
X428532Y184343D03*
Y188280D03*
X424595Y196154D03*
X420658D03*
X424595Y184343D03*
X420658Y192217D03*
X424595Y207965D03*
X412784Y204028D03*
X428532Y215839D03*
X420658Y200091D03*
X416721Y211902D03*
X424595D03*
Y215839D03*
X416721Y207965D03*
X412784D03*
X420658Y215839D03*
X416721D03*
Y200091D03*
X412784D03*
Y211902D03*
Y215839D03*
X428532Y200091D03*
Y204028D03*
Y207965D03*
X424595Y200091D03*
Y204028D03*
X420658D03*
X416721D03*
X420658Y207965D03*
Y211902D03*
X428532D03*
X436406Y133161D03*
X432469Y144973D03*
X440343Y141035D03*
X444280D03*
Y137098D03*
X440343D03*
X436406D03*
X440343Y144973D03*
X444280Y133161D03*
X440343D03*
X436406Y144973D03*
Y141035D03*
X432469D03*
Y137098D03*
Y133161D03*
X444280Y144973D03*
Y148910D03*
X436406Y156784D03*
X432469Y160721D03*
X444280Y156784D03*
X440343Y160721D03*
X444280D03*
X440343Y156784D03*
X436406Y160721D03*
Y152847D03*
X432469Y156784D03*
X440343Y152847D03*
X436406Y148910D03*
X432469Y152847D03*
Y148910D03*
X440343D03*
X444280Y152847D03*
X440343Y168595D03*
X444280Y164658D03*
X436406Y172532D03*
X444280D03*
X440343Y176469D03*
X432469D03*
X444280D03*
Y168595D03*
X440343Y164658D03*
Y180406D03*
Y172532D03*
X432469D03*
Y180406D03*
X436406D03*
X432469Y168595D03*
Y164658D03*
X444280Y180406D03*
X436406Y176469D03*
Y168595D03*
Y164658D03*
X444280Y188280D03*
X432469Y184343D03*
X436406Y192217D03*
X432469Y188280D03*
Y192217D03*
Y196154D03*
X440343Y192217D03*
X444280Y196154D03*
X436406Y184343D03*
X440343Y188280D03*
X444280Y192217D03*
X436406Y196154D03*
X440343D03*
Y184343D03*
X444280D03*
X436406Y188280D03*
Y211902D03*
X440343Y200091D03*
X444280Y207965D03*
X432469Y204028D03*
X436406Y207965D03*
X432469D03*
X436406Y200091D03*
Y204028D03*
X432469Y200091D03*
X436406Y215839D03*
X432469D03*
Y211902D03*
X440343Y204028D03*
X444280D03*
X440343Y211902D03*
X444280D03*
Y200091D03*
X440343Y215839D03*
X444280D03*
X440343Y207965D03*
X460028Y141035D03*
X448217Y137098D03*
X456091Y133161D03*
X452154Y144973D03*
X463965Y141035D03*
X452154D03*
X456091D03*
X460028Y133161D03*
X463965D03*
X460028Y137098D03*
X463965D03*
X452154D03*
X456091D03*
X448217Y133161D03*
X452154D03*
X448217Y144973D03*
X456091D03*
X460028D03*
X463965D03*
X448217Y141035D03*
X456091Y152847D03*
X448217Y160721D03*
X463965Y148910D03*
X460028Y160721D03*
X448217Y156784D03*
X463965Y160721D03*
Y156784D03*
X456091Y160721D03*
Y156784D03*
X460028D03*
X463965Y152847D03*
X448217D03*
X452154D03*
X456091Y148910D03*
X460028Y152847D03*
Y148910D03*
X448217D03*
X452154D03*
Y156784D03*
Y160721D03*
X463965Y168595D03*
X460028Y180406D03*
X448217Y176469D03*
Y168595D03*
X456091Y172532D03*
X448217Y164658D03*
Y172532D03*
X460028Y164658D03*
X463965D03*
X456091D03*
X463965Y180406D03*
X456091D03*
X460028Y172532D03*
Y176469D03*
X463965Y172532D03*
Y176469D03*
X456091Y168595D03*
X460028D03*
X448217Y180406D03*
X452154D03*
X456091Y176469D03*
X452154Y164658D03*
Y168595D03*
Y172532D03*
Y176469D03*
X456091Y192217D03*
X463965Y188280D03*
X452154Y184343D03*
X448217Y196154D03*
X460028Y184343D03*
X463965D03*
Y192217D03*
X452154Y196154D03*
X448217Y192217D03*
X452154D03*
X456091Y196154D03*
X460028Y188280D03*
Y196154D03*
Y192217D03*
X448217Y184343D03*
Y188280D03*
X452154D03*
X456091D03*
Y184343D03*
X463965Y196154D03*
Y207965D03*
X452154Y204028D03*
X448217Y215839D03*
X460028Y200091D03*
X456091Y211902D03*
X463965D03*
Y215839D03*
X460028Y211902D03*
Y215839D03*
X448217Y204028D03*
Y207965D03*
Y211902D03*
X452154D03*
Y215839D03*
X456091D03*
X448217Y200091D03*
X452154D03*
X456091D03*
Y204028D03*
X463965Y200091D03*
Y204028D03*
X460028D03*
Y207965D03*
X452154D03*
X456091D03*
X471839Y144973D03*
X467902Y137098D03*
Y141035D03*
X471839D03*
Y137098D03*
X467902Y133161D03*
X471839D03*
X467902Y144973D03*
Y156784D03*
Y160721D03*
X471839D03*
Y156784D03*
Y152847D03*
X467902D03*
Y148910D03*
X471839D03*
X467902Y176469D03*
X471839Y164658D03*
X467902Y168595D03*
Y172532D03*
Y164658D03*
X471839Y168595D03*
Y172532D03*
Y176469D03*
X467902Y180406D03*
X471839D03*
Y184343D03*
X467902Y196154D03*
Y184343D03*
Y188280D03*
X471839D03*
Y192217D03*
Y196154D03*
X467902Y192217D03*
X471839Y204028D03*
X467902Y215839D03*
Y207965D03*
Y211902D03*
Y200091D03*
X471839D03*
X467902Y204028D03*
X471839Y207965D03*
Y211902D03*
Y215839D03*
G54D49*
X159669Y317000D03*
Y327000D03*
X168331Y317000D03*
Y327000D03*
G54D94*
X474000Y243650D03*
Y254150D03*
G54D58*
X173967Y297112D03*
X516767Y266312D03*
X568467Y63512D03*
G54D67*
X323744Y286500D03*
Y276500D03*
X344256Y286500D03*
Y276500D03*
X550544Y262100D03*
Y282100D03*
Y272100D03*
Y292100D03*
Y302100D03*
X571056Y262100D03*
Y282100D03*
Y272100D03*
Y302100D03*
Y292100D03*
X601844Y261500D03*
Y281500D03*
Y271500D03*
Y291500D03*
Y301500D03*
X622356Y261500D03*
Y281500D03*
Y271500D03*
Y301500D03*
Y291500D03*
G54D86*
X414400Y399200D03*
G54D95*
X478656Y367205D03*
Y375079D03*
Y382953D03*
Y390827D03*
X491549Y367205D03*
Y375079D03*
Y382953D03*
Y390827D03*
G54D77*
X389231Y288533D03*
Y300467D03*
X391200Y288533D03*
X393169D03*
X391200Y300467D03*
X393169D03*
X596047Y214382D03*
X598016D03*
X599984D03*
X601953D03*
Y204418D03*
X599984D03*
X598016D03*
X596047D03*
G54D68*
X338016Y222296D03*
X339984D03*
X336047D03*
X339984Y240504D03*
X336047D03*
X338016D03*
X341953Y222296D03*
Y240504D03*
G54D59*
X173967Y305888D03*
X516767Y275088D03*
X568467Y72288D03*
G54D87*
X404740Y393294D03*
Y405106D03*
X424060D03*
Y393294D03*
G54D69*
X332848Y230416D03*
Y226479D03*
Y228447D03*
Y224510D03*
Y222542D03*
Y232384D03*
Y236321D03*
Y238290D03*
Y240258D03*
Y234353D03*
X345152Y230416D03*
Y228447D03*
Y226479D03*
Y224510D03*
Y222542D03*
Y232384D03*
Y234353D03*
Y236321D03*
Y238290D03*
Y240258D03*
G54D78*
X386812Y288533D03*
G54D96*
X529750Y147000D03*
X519250D03*
X529750Y134500D03*
X519250D03*
X529750Y159500D03*
X519250D03*
G54D88*
X404890Y395263D03*
Y397231D03*
Y399200D03*
Y401169D03*
Y403137D03*
X423910D03*
Y401169D03*
Y399200D03*
Y397231D03*
Y395263D03*
G54D79*
X386812Y300467D03*
G54D97*
X529108Y330600D03*
X555092D03*
G54D89*
X429225Y282679D03*
Y284647D03*
Y286616D03*
Y288584D03*
Y290553D03*
Y292521D03*
X441975Y284647D03*
Y292521D03*
Y290553D03*
Y288584D03*
Y286616D03*
G54D98*
X528300Y415049D03*
Y420953D03*
X543504Y407875D03*
Y421654D03*
Y413779D03*
Y427558D03*
X567126Y407875D03*
X555315D03*
Y421654D03*
X567126Y413779D03*
X555315D03*
X567126Y421654D03*
X555315Y427558D03*
X567126D03*
X578937Y407875D03*
Y413779D03*
Y421654D03*
Y427558D03*
X590748Y407875D03*
X602559D03*
Y421654D03*
X590748Y413779D03*
X602559D03*
Y427558D03*
X614370Y407875D03*
Y421654D03*
Y413779D03*
Y427558D03*
G54D99*
X552087Y209988D03*
Y212154D03*
Y214319D03*
X562913D03*
Y212154D03*
Y209988D03*
M02*
